FILE_TYPE = MACRO_DRAWING;
SET COLOR_WIRE YELLOW;
SET COLOR_PROP ORANGE;
SET COLOR_DOT WHITE;
SET COLOR_ARC YELLOW;
SET COLOR_BODY GREEN;
SET COLOR_NOTE PURPLE;
SET PROP_DISPLAY VALUE;
SET PAGE_NUMBER P107;
FORCEADD UNIVERSAL_GND..1
(-2275 0);
FORCEPROP 3 LASTPIN (-2275 50) SIG_NAME GND\g
J 0
(-2265 60);
DISPLAY 0.659574 (-2265 60);
PAINT MONO (-2265 60);
DISPLAY INVISIBLE (-2265 60);
FORCEPROP 1 LAST PATH I1
J 0
(-2200 0);
DISPLAY 0.872340 (-2200 0);
PAINT AQUA (-2200 0);
DISPLAY INVISIBLE (-2200 0);
FORCEPROP 1 LAST HDL_POWER GND
J 1
(-2250 -75);
DISPLAY 0.872340 (-2250 -75);
PAINT GREEN (-2250 -75);
DISPLAY INVISIBLE (-2250 -75);
FORCEPROP 2 LAST CDS_LIB logical_power
J 0
(-2275 0);
PAINT MONO (-2275 0);
DISPLAY INVISIBLE (-2275 0);
FORCEADD OFFPAGE..1
(-3450 2025);
FORCEPROP 2 LAST $XR1 106 
J 0
(-3821 2025);
DISPLAY 0.638298 (-3821 2025);
PAINT MONO (-3821 2025);
FORCEPROP 2 LAST $XR0 55 
J 0
(-3701 2025);
DISPLAY 0.638298 (-3701 2025);
PAINT MONO (-3701 2025);
FORCEPROP 2 LAST CDS_LIB standard
J 0
(-3450 2025);
PAINT MONO (-3450 2025);
DISPLAY INVISIBLE (-3450 2025);
FORCEPROP 1 LAST OFFPAGE TRUE
J 0
(-3125 1900);
DISPLAY 0.872340 (-3125 1900);
DISPLAY INVISIBLE (-3125 1900);
FORCEPROP 1 LAST COMMENT_BODY TRUE
J 0
(-3325 1925);
DISPLAY 0.872340 (-3325 1925);
PAINT GREEN (-3325 1925);
DISPLAY INVISIBLE (-3325 1925);
FORCEPROP 2 LAST PATH I10
J 0
(-3400 2100);
DISPLAY 1.021277 (-3400 2100);
DISPLAY INVISIBLE (-3400 2100);
FORCEADD TAP..1
(-850 3475);
FORCEPROP 3 LASTPIN (-900 3475) SIG_NAME M_E_CPU1_SA_DQ<13>
J 0
(-890 3485);
DISPLAY 0.659574 (-890 3485);
PAINT MONO (-890 3485);
DISPLAY INVISIBLE (-890 3485);
FORCEPROP 1 LASTPIN (-900 3475) BN 13
J 0
(-912 3483);
DISPLAY 0.680851 (-912 3483);
PAINT GREEN (-912 3483);
FORCEPROP 2 LAST CDS_LIB standard
J 0
(-850 3475);
PAINT MONO (-850 3475);
DISPLAY INVISIBLE (-850 3475);
FORCEPROP 1 LAST BODY_TYPE PLUMBING
J 0
(-850 3525);
DISPLAY 0.872340 (-850 3525);
PAINT GREEN (-850 3525);
DISPLAY INVISIBLE (-850 3525);
FORCEPROP 1 LAST HDL_TAP TRUE
J 0
(-525 3350);
DISPLAY 0.872340 (-525 3350);
DISPLAY INVISIBLE (-525 3350);
FORCEPROP 1 LAST PATH I100
J 0
(-852 3475);
DISPLAY 0.872340 (-852 3475);
PAINT GREEN (-852 3475);
DISPLAY INVISIBLE (-852 3475);
FORCEADD TAP..1
(-850 3525);
FORCEPROP 3 LASTPIN (-900 3525) SIG_NAME M_E_CPU1_SA_DQ<14>
J 0
(-890 3535);
DISPLAY 0.659574 (-890 3535);
PAINT MONO (-890 3535);
DISPLAY INVISIBLE (-890 3535);
FORCEPROP 1 LASTPIN (-900 3525) BN 14
J 0
(-912 3533);
DISPLAY 0.680851 (-912 3533);
PAINT GREEN (-912 3533);
FORCEPROP 2 LAST CDS_LIB standard
J 0
(-850 3525);
PAINT MONO (-850 3525);
DISPLAY INVISIBLE (-850 3525);
FORCEPROP 1 LAST BODY_TYPE PLUMBING
J 0
(-850 3575);
DISPLAY 0.872340 (-850 3575);
PAINT GREEN (-850 3575);
DISPLAY INVISIBLE (-850 3575);
FORCEPROP 1 LAST HDL_TAP TRUE
J 0
(-525 3400);
DISPLAY 0.872340 (-525 3400);
DISPLAY INVISIBLE (-525 3400);
FORCEPROP 1 LAST PATH I101
J 0
(-852 3525);
DISPLAY 0.872340 (-852 3525);
PAINT GREEN (-852 3525);
DISPLAY INVISIBLE (-852 3525);
FORCEADD TAP..1
(-850 3675);
FORCEPROP 3 LASTPIN (-900 3675) SIG_NAME M_E_CPU1_SA_DQ<17>
J 0
(-890 3685);
DISPLAY 0.659574 (-890 3685);
PAINT MONO (-890 3685);
DISPLAY INVISIBLE (-890 3685);
FORCEPROP 1 LASTPIN (-900 3675) BN 17
J 0
(-912 3683);
DISPLAY 0.680851 (-912 3683);
PAINT GREEN (-912 3683);
FORCEPROP 2 LAST CDS_LIB standard
J 0
(-850 3675);
PAINT MONO (-850 3675);
DISPLAY INVISIBLE (-850 3675);
FORCEPROP 1 LAST BODY_TYPE PLUMBING
J 0
(-850 3725);
DISPLAY 0.872340 (-850 3725);
PAINT GREEN (-850 3725);
DISPLAY INVISIBLE (-850 3725);
FORCEPROP 1 LAST HDL_TAP TRUE
J 0
(-525 3550);
DISPLAY 0.872340 (-525 3550);
DISPLAY INVISIBLE (-525 3550);
FORCEPROP 1 LAST PATH I102
J 0
(-852 3675);
DISPLAY 0.872340 (-852 3675);
PAINT GREEN (-852 3675);
DISPLAY INVISIBLE (-852 3675);
FORCEADD TAP..1
(-850 3725);
FORCEPROP 3 LASTPIN (-900 3725) SIG_NAME M_E_CPU1_SA_DQ<18>
J 0
(-890 3735);
DISPLAY 0.659574 (-890 3735);
PAINT MONO (-890 3735);
DISPLAY INVISIBLE (-890 3735);
FORCEPROP 1 LASTPIN (-900 3725) BN 18
J 0
(-912 3733);
DISPLAY 0.680851 (-912 3733);
PAINT GREEN (-912 3733);
FORCEPROP 2 LAST CDS_LIB standard
J 0
(-850 3725);
PAINT MONO (-850 3725);
DISPLAY INVISIBLE (-850 3725);
FORCEPROP 1 LAST BODY_TYPE PLUMBING
J 0
(-850 3775);
DISPLAY 0.872340 (-850 3775);
PAINT GREEN (-850 3775);
DISPLAY INVISIBLE (-850 3775);
FORCEPROP 1 LAST HDL_TAP TRUE
J 0
(-525 3600);
DISPLAY 0.872340 (-525 3600);
DISPLAY INVISIBLE (-525 3600);
FORCEPROP 1 LAST PATH I103
J 0
(-852 3725);
DISPLAY 0.872340 (-852 3725);
PAINT GREEN (-852 3725);
DISPLAY INVISIBLE (-852 3725);
FORCEADD TAP..1
(-850 3775);
FORCEPROP 3 LASTPIN (-900 3775) SIG_NAME M_E_CPU1_SA_DQ<19>
J 0
(-890 3785);
DISPLAY 0.659574 (-890 3785);
PAINT MONO (-890 3785);
DISPLAY INVISIBLE (-890 3785);
FORCEPROP 1 LASTPIN (-900 3775) BN 19
J 0
(-912 3783);
DISPLAY 0.680851 (-912 3783);
PAINT GREEN (-912 3783);
FORCEPROP 2 LAST CDS_LIB standard
J 0
(-850 3775);
PAINT MONO (-850 3775);
DISPLAY INVISIBLE (-850 3775);
FORCEPROP 1 LAST BODY_TYPE PLUMBING
J 0
(-850 3825);
DISPLAY 0.872340 (-850 3825);
PAINT GREEN (-850 3825);
DISPLAY INVISIBLE (-850 3825);
FORCEPROP 1 LAST HDL_TAP TRUE
J 0
(-525 3650);
DISPLAY 0.872340 (-525 3650);
DISPLAY INVISIBLE (-525 3650);
FORCEPROP 1 LAST PATH I104
J 0
(-852 3775);
DISPLAY 0.872340 (-852 3775);
PAINT GREEN (-852 3775);
DISPLAY INVISIBLE (-852 3775);
FORCEADD TAP..1
(-850 3825);
FORCEPROP 3 LASTPIN (-900 3825) SIG_NAME M_E_CPU1_SA_DQ<20>
J 0
(-890 3835);
DISPLAY 0.659574 (-890 3835);
PAINT MONO (-890 3835);
DISPLAY INVISIBLE (-890 3835);
FORCEPROP 1 LASTPIN (-900 3825) BN 20
J 0
(-912 3833);
DISPLAY 0.680851 (-912 3833);
PAINT GREEN (-912 3833);
FORCEPROP 2 LAST CDS_LIB standard
J 0
(-850 3825);
PAINT MONO (-850 3825);
DISPLAY INVISIBLE (-850 3825);
FORCEPROP 1 LAST BODY_TYPE PLUMBING
J 0
(-850 3875);
DISPLAY 0.872340 (-850 3875);
PAINT GREEN (-850 3875);
DISPLAY INVISIBLE (-850 3875);
FORCEPROP 1 LAST HDL_TAP TRUE
J 0
(-525 3700);
DISPLAY 0.872340 (-525 3700);
DISPLAY INVISIBLE (-525 3700);
FORCEPROP 1 LAST PATH I105
J 0
(-852 3825);
DISPLAY 0.872340 (-852 3825);
PAINT GREEN (-852 3825);
DISPLAY INVISIBLE (-852 3825);
FORCEADD TAP..1
(-850 3625);
FORCEPROP 3 LASTPIN (-900 3625) SIG_NAME M_E_CPU1_SA_DQ<16>
J 0
(-890 3635);
DISPLAY 0.659574 (-890 3635);
PAINT MONO (-890 3635);
DISPLAY INVISIBLE (-890 3635);
FORCEPROP 1 LASTPIN (-900 3625) BN 16
J 0
(-912 3633);
DISPLAY 0.680851 (-912 3633);
PAINT GREEN (-912 3633);
FORCEPROP 2 LAST CDS_LIB standard
J 0
(-850 3625);
PAINT MONO (-850 3625);
DISPLAY INVISIBLE (-850 3625);
FORCEPROP 1 LAST BODY_TYPE PLUMBING
J 0
(-850 3675);
DISPLAY 0.872340 (-850 3675);
PAINT GREEN (-850 3675);
DISPLAY INVISIBLE (-850 3675);
FORCEPROP 1 LAST HDL_TAP TRUE
J 0
(-525 3500);
DISPLAY 0.872340 (-525 3500);
DISPLAY INVISIBLE (-525 3500);
FORCEPROP 1 LAST PATH I106
J 0
(-852 3625);
DISPLAY 0.872340 (-852 3625);
PAINT GREEN (-852 3625);
DISPLAY INVISIBLE (-852 3625);
FORCEADD TAP..1
(-850 3875);
FORCEPROP 3 LASTPIN (-900 3875) SIG_NAME M_E_CPU1_SA_DQ<21>
J 0
(-890 3885);
DISPLAY 0.659574 (-890 3885);
PAINT MONO (-890 3885);
DISPLAY INVISIBLE (-890 3885);
FORCEPROP 1 LASTPIN (-900 3875) BN 21
J 0
(-912 3883);
DISPLAY 0.680851 (-912 3883);
PAINT GREEN (-912 3883);
FORCEPROP 2 LAST CDS_LIB standard
J 0
(-850 3875);
PAINT MONO (-850 3875);
DISPLAY INVISIBLE (-850 3875);
FORCEPROP 1 LAST BODY_TYPE PLUMBING
J 0
(-850 3925);
DISPLAY 0.872340 (-850 3925);
PAINT GREEN (-850 3925);
DISPLAY INVISIBLE (-850 3925);
FORCEPROP 1 LAST HDL_TAP TRUE
J 0
(-525 3750);
DISPLAY 0.872340 (-525 3750);
DISPLAY INVISIBLE (-525 3750);
FORCEPROP 1 LAST PATH I107
J 0
(-852 3875);
DISPLAY 0.872340 (-852 3875);
PAINT GREEN (-852 3875);
DISPLAY INVISIBLE (-852 3875);
FORCEADD TAP..1
(-850 3925);
FORCEPROP 3 LASTPIN (-900 3925) SIG_NAME M_E_CPU1_SA_DQ<22>
J 0
(-890 3935);
DISPLAY 0.659574 (-890 3935);
PAINT MONO (-890 3935);
DISPLAY INVISIBLE (-890 3935);
FORCEPROP 1 LASTPIN (-900 3925) BN 22
J 0
(-912 3933);
DISPLAY 0.680851 (-912 3933);
PAINT GREEN (-912 3933);
FORCEPROP 2 LAST CDS_LIB standard
J 0
(-850 3925);
DISPLAY INVISIBLE (-850 3925);
FORCEPROP 1 LAST BODY_TYPE PLUMBING
J 0
(-850 3975);
DISPLAY 0.872340 (-850 3975);
PAINT GREEN (-850 3975);
DISPLAY INVISIBLE (-850 3975);
FORCEPROP 1 LAST HDL_TAP TRUE
J 0
(-525 3800);
DISPLAY 0.872340 (-525 3800);
DISPLAY INVISIBLE (-525 3800);
FORCEPROP 1 LAST PATH I108
J 0
(-852 3925);
DISPLAY 0.872340 (-852 3925);
PAINT GREEN (-852 3925);
DISPLAY INVISIBLE (-852 3925);
FORCEADD TAP..1
(-850 3975);
FORCEPROP 3 LASTPIN (-900 3975) SIG_NAME M_E_CPU1_SA_DQ<23>
J 0
(-890 3985);
DISPLAY 0.659574 (-890 3985);
PAINT MONO (-890 3985);
DISPLAY INVISIBLE (-890 3985);
FORCEPROP 1 LASTPIN (-900 3975) BN 23
J 0
(-912 3983);
DISPLAY 0.680851 (-912 3983);
PAINT GREEN (-912 3983);
FORCEPROP 2 LAST CDS_LIB standard
J 0
(-850 3975);
DISPLAY INVISIBLE (-850 3975);
FORCEPROP 1 LAST BODY_TYPE PLUMBING
J 0
(-850 4025);
DISPLAY 0.872340 (-850 4025);
PAINT GREEN (-850 4025);
DISPLAY INVISIBLE (-850 4025);
FORCEPROP 1 LAST HDL_TAP TRUE
J 0
(-525 3850);
DISPLAY 0.872340 (-525 3850);
DISPLAY INVISIBLE (-525 3850);
FORCEPROP 1 LAST PATH I109
J 0
(-852 3975);
DISPLAY 0.872340 (-852 3975);
PAINT GREEN (-852 3975);
DISPLAY INVISIBLE (-852 3975);
FORCEADD OFFPAGE..1
(-3450 2125);
FORCEPROP 2 LAST $XR3 109 
J 0
(-3852 2089);
DISPLAY 0.638298 (-3852 2089);
PAINT MONO (-3852 2089);
FORCEPROP 2 LAST $XR2 108 
J 0
(-3732 2089);
DISPLAY 0.638298 (-3732 2089);
PAINT MONO (-3732 2089);
FORCEPROP 2 LAST $XR1 106 
J 0
(-3852 2125);
DISPLAY 0.638298 (-3852 2125);
PAINT MONO (-3852 2125);
FORCEPROP 2 LAST $XR0 130 
J 0
(-3732 2125);
DISPLAY 0.638298 (-3732 2125);
PAINT MONO (-3732 2125);
FORCEPROP 2 LAST CDS_LIB standard
J 0
(-3450 2125);
PAINT MONO (-3450 2125);
DISPLAY INVISIBLE (-3450 2125);
FORCEPROP 1 LAST OFFPAGE TRUE
J 0
(-3125 2000);
DISPLAY 0.872340 (-3125 2000);
DISPLAY INVISIBLE (-3125 2000);
FORCEPROP 1 LAST COMMENT_BODY TRUE
J 0
(-3325 2025);
DISPLAY 0.872340 (-3325 2025);
PAINT GREEN (-3325 2025);
DISPLAY INVISIBLE (-3325 2025);
FORCEPROP 2 LAST PATH I11
J 0
(-3400 2200);
DISPLAY 1.021277 (-3400 2200);
DISPLAY INVISIBLE (-3400 2200);
FORCEADD TAP..1
(-850 4075);
FORCEPROP 3 LASTPIN (-900 4075) SIG_NAME M_E_CPU1_SA_DQ<25>
J 0
(-890 4085);
DISPLAY 0.659574 (-890 4085);
PAINT MONO (-890 4085);
DISPLAY INVISIBLE (-890 4085);
FORCEPROP 1 LASTPIN (-900 4075) BN 25
J 0
(-912 4083);
DISPLAY 0.680851 (-912 4083);
PAINT GREEN (-912 4083);
FORCEPROP 2 LAST CDS_LIB standard
J 0
(-850 4075);
DISPLAY INVISIBLE (-850 4075);
FORCEPROP 1 LAST BODY_TYPE PLUMBING
J 0
(-850 4125);
DISPLAY 0.872340 (-850 4125);
PAINT GREEN (-850 4125);
DISPLAY INVISIBLE (-850 4125);
FORCEPROP 1 LAST HDL_TAP TRUE
J 0
(-525 3950);
DISPLAY 0.872340 (-525 3950);
DISPLAY INVISIBLE (-525 3950);
FORCEPROP 1 LAST PATH I110
J 0
(-852 4075);
DISPLAY 0.872340 (-852 4075);
PAINT GREEN (-852 4075);
DISPLAY INVISIBLE (-852 4075);
FORCEADD TAP..1
(-850 4025);
FORCEPROP 3 LASTPIN (-900 4025) SIG_NAME M_E_CPU1_SA_DQ<24>
J 0
(-890 4035);
DISPLAY 0.659574 (-890 4035);
PAINT MONO (-890 4035);
DISPLAY INVISIBLE (-890 4035);
FORCEPROP 1 LASTPIN (-900 4025) BN 24
J 0
(-912 4033);
DISPLAY 0.680851 (-912 4033);
PAINT GREEN (-912 4033);
FORCEPROP 2 LAST CDS_LIB standard
J 0
(-850 4025);
DISPLAY INVISIBLE (-850 4025);
FORCEPROP 1 LAST BODY_TYPE PLUMBING
J 0
(-850 4075);
DISPLAY 0.872340 (-850 4075);
PAINT GREEN (-850 4075);
DISPLAY INVISIBLE (-850 4075);
FORCEPROP 1 LAST HDL_TAP TRUE
J 0
(-525 3900);
DISPLAY 0.872340 (-525 3900);
DISPLAY INVISIBLE (-525 3900);
FORCEPROP 1 LAST PATH I111
J 0
(-852 4025);
DISPLAY 0.872340 (-852 4025);
PAINT GREEN (-852 4025);
DISPLAY INVISIBLE (-852 4025);
FORCEADD TAP..1
(-850 4125);
FORCEPROP 3 LASTPIN (-900 4125) SIG_NAME M_E_CPU1_SA_DQ<26>
J 0
(-890 4135);
DISPLAY 0.659574 (-890 4135);
PAINT MONO (-890 4135);
DISPLAY INVISIBLE (-890 4135);
FORCEPROP 1 LASTPIN (-900 4125) BN 26
J 0
(-912 4133);
DISPLAY 0.680851 (-912 4133);
PAINT GREEN (-912 4133);
FORCEPROP 2 LAST CDS_LIB standard
J 0
(-850 4125);
DISPLAY INVISIBLE (-850 4125);
FORCEPROP 1 LAST BODY_TYPE PLUMBING
J 0
(-850 4175);
DISPLAY 0.872340 (-850 4175);
PAINT GREEN (-850 4175);
DISPLAY INVISIBLE (-850 4175);
FORCEPROP 1 LAST HDL_TAP TRUE
J 0
(-525 4000);
DISPLAY 0.872340 (-525 4000);
DISPLAY INVISIBLE (-525 4000);
FORCEPROP 1 LAST PATH I112
J 0
(-852 4125);
DISPLAY 0.872340 (-852 4125);
PAINT GREEN (-852 4125);
DISPLAY INVISIBLE (-852 4125);
FORCEADD TAP..1
(-850 4175);
FORCEPROP 3 LASTPIN (-900 4175) SIG_NAME M_E_CPU1_SA_DQ<27>
J 0
(-890 4185);
DISPLAY 0.659574 (-890 4185);
PAINT MONO (-890 4185);
DISPLAY INVISIBLE (-890 4185);
FORCEPROP 1 LASTPIN (-900 4175) BN 27
J 0
(-912 4183);
DISPLAY 0.680851 (-912 4183);
PAINT GREEN (-912 4183);
FORCEPROP 2 LAST CDS_LIB standard
J 0
(-850 4175);
DISPLAY INVISIBLE (-850 4175);
FORCEPROP 1 LAST BODY_TYPE PLUMBING
J 0
(-850 4225);
DISPLAY 0.872340 (-850 4225);
PAINT GREEN (-850 4225);
DISPLAY INVISIBLE (-850 4225);
FORCEPROP 1 LAST HDL_TAP TRUE
J 0
(-525 4050);
DISPLAY 0.872340 (-525 4050);
DISPLAY INVISIBLE (-525 4050);
FORCEPROP 1 LAST PATH I113
J 0
(-852 4175);
DISPLAY 0.872340 (-852 4175);
PAINT GREEN (-852 4175);
DISPLAY INVISIBLE (-852 4175);
FORCEADD TAP..1
(-850 4225);
FORCEPROP 3 LASTPIN (-900 4225) SIG_NAME M_E_CPU1_SA_DQ<28>
J 0
(-890 4235);
DISPLAY 0.659574 (-890 4235);
PAINT MONO (-890 4235);
DISPLAY INVISIBLE (-890 4235);
FORCEPROP 1 LASTPIN (-900 4225) BN 28
J 0
(-912 4233);
DISPLAY 0.680851 (-912 4233);
PAINT GREEN (-912 4233);
FORCEPROP 2 LAST CDS_LIB standard
J 0
(-850 4225);
DISPLAY INVISIBLE (-850 4225);
FORCEPROP 1 LAST BODY_TYPE PLUMBING
J 0
(-850 4275);
DISPLAY 0.872340 (-850 4275);
PAINT GREEN (-850 4275);
DISPLAY INVISIBLE (-850 4275);
FORCEPROP 1 LAST HDL_TAP TRUE
J 0
(-525 4100);
DISPLAY 0.872340 (-525 4100);
DISPLAY INVISIBLE (-525 4100);
FORCEPROP 1 LAST PATH I114
J 0
(-852 4225);
DISPLAY 0.872340 (-852 4225);
PAINT GREEN (-852 4225);
DISPLAY INVISIBLE (-852 4225);
FORCEADD TAP..1
(-850 4325);
FORCEPROP 3 LASTPIN (-900 4325) SIG_NAME M_E_CPU1_SA_DQ<30>
J 0
(-890 4335);
DISPLAY 0.659574 (-890 4335);
PAINT MONO (-890 4335);
DISPLAY INVISIBLE (-890 4335);
FORCEPROP 1 LASTPIN (-900 4325) BN 30
J 0
(-912 4333);
DISPLAY 0.680851 (-912 4333);
PAINT GREEN (-912 4333);
FORCEPROP 2 LAST CDS_LIB standard
J 0
(-850 4325);
DISPLAY INVISIBLE (-850 4325);
FORCEPROP 1 LAST BODY_TYPE PLUMBING
J 0
(-850 4375);
DISPLAY 0.872340 (-850 4375);
PAINT GREEN (-850 4375);
DISPLAY INVISIBLE (-850 4375);
FORCEPROP 1 LAST HDL_TAP TRUE
J 0
(-525 4200);
DISPLAY 0.872340 (-525 4200);
DISPLAY INVISIBLE (-525 4200);
FORCEPROP 1 LAST PATH I115
J 0
(-852 4325);
DISPLAY 0.872340 (-852 4325);
PAINT GREEN (-852 4325);
DISPLAY INVISIBLE (-852 4325);
FORCEADD TAP..1
(-850 4275);
FORCEPROP 3 LASTPIN (-900 4275) SIG_NAME M_E_CPU1_SA_DQ<29>
J 0
(-890 4285);
DISPLAY 0.659574 (-890 4285);
PAINT MONO (-890 4285);
DISPLAY INVISIBLE (-890 4285);
FORCEPROP 1 LASTPIN (-900 4275) BN 29
J 0
(-912 4283);
DISPLAY 0.680851 (-912 4283);
PAINT GREEN (-912 4283);
FORCEPROP 2 LAST CDS_LIB standard
J 0
(-850 4275);
DISPLAY INVISIBLE (-850 4275);
FORCEPROP 1 LAST BODY_TYPE PLUMBING
J 0
(-850 4325);
DISPLAY 0.872340 (-850 4325);
PAINT GREEN (-850 4325);
DISPLAY INVISIBLE (-850 4325);
FORCEPROP 1 LAST HDL_TAP TRUE
J 0
(-525 4150);
DISPLAY 0.872340 (-525 4150);
DISPLAY INVISIBLE (-525 4150);
FORCEPROP 1 LAST PATH I116
J 0
(-852 4275);
DISPLAY 0.872340 (-852 4275);
PAINT GREEN (-852 4275);
DISPLAY INVISIBLE (-852 4275);
FORCEADD OFFPAGE..1
(-3425 4400);
FORCEPROP 2 LAST $XR1 106 
J 0
(-3766 4400);
DISPLAY 0.638298 (-3766 4400);
PAINT MONO (-3766 4400);
FORCEPROP 2 LAST $XR0 55 
J 0
(-3646 4400);
DISPLAY 0.638298 (-3646 4400);
PAINT MONO (-3646 4400);
FORCEPROP 2 LAST CDS_LIB standard
J 0
(-3425 4400);
PAINT MONO (-3425 4400);
DISPLAY INVISIBLE (-3425 4400);
FORCEPROP 1 LAST OFFPAGE TRUE
J 0
(-3100 4275);
DISPLAY 0.872340 (-3100 4275);
DISPLAY INVISIBLE (-3100 4275);
FORCEPROP 1 LAST COMMENT_BODY TRUE
J 0
(-3300 4300);
DISPLAY 0.872340 (-3300 4300);
PAINT GREEN (-3300 4300);
DISPLAY INVISIBLE (-3300 4300);
FORCEPROP 2 LAST PATH I117
J 0
(-3375 4475);
DISPLAY 1.021277 (-3375 4475);
DISPLAY INVISIBLE (-3375 4475);
FORCEADD TAP..1
R 2
(-2500 4375);
FORCEPROP 3 LASTPIN (-2450 4375) SIG_NAME M_E_CPU1_SA_CA<6>
J 0
(-2440 4385);
DISPLAY 0.659574 (-2440 4385);
PAINT MONO (-2440 4385);
DISPLAY INVISIBLE (-2440 4385);
FORCEPROP 1 LASTPIN (-2450 4375) BN 6
J 2
(-2438 4383);
DISPLAY 0.680851 (-2438 4383);
PAINT GREEN (-2438 4383);
FORCEPROP 2 LAST CDS_LIB standard
J 0
(-2500 4375);
DISPLAY INVISIBLE (-2500 4375);
FORCEPROP 1 LAST BODY_TYPE PLUMBING
J 2
(-2500 4425);
DISPLAY 0.872340 (-2500 4425);
PAINT GREEN (-2500 4425);
DISPLAY INVISIBLE (-2500 4425);
FORCEPROP 1 LAST HDL_TAP TRUE
J 2
(-2825 4250);
DISPLAY 0.872340 (-2825 4250);
DISPLAY INVISIBLE (-2825 4250);
FORCEPROP 1 LAST PATH I118
J 2
(-2498 4375);
DISPLAY 0.872340 (-2498 4375);
PAINT GREEN (-2498 4375);
DISPLAY INVISIBLE (-2498 4375);
FORCEADD TAP..1
(-850 4375);
FORCEPROP 3 LASTPIN (-900 4375) SIG_NAME M_E_CPU1_SA_DQ<31>
J 0
(-890 4385);
DISPLAY 0.659574 (-890 4385);
PAINT MONO (-890 4385);
DISPLAY INVISIBLE (-890 4385);
FORCEPROP 1 LASTPIN (-900 4375) BN 31
J 0
(-912 4383);
DISPLAY 0.680851 (-912 4383);
PAINT GREEN (-912 4383);
FORCEPROP 2 LAST CDS_LIB standard
J 0
(-850 4375);
DISPLAY INVISIBLE (-850 4375);
FORCEPROP 1 LAST BODY_TYPE PLUMBING
J 0
(-850 4425);
DISPLAY 0.872340 (-850 4425);
PAINT GREEN (-850 4425);
DISPLAY INVISIBLE (-850 4425);
FORCEPROP 1 LAST HDL_TAP TRUE
J 0
(-525 4250);
DISPLAY 0.872340 (-525 4250);
DISPLAY INVISIBLE (-525 4250);
FORCEPROP 1 LAST PATH I119
J 0
(-852 4375);
DISPLAY 0.872340 (-852 4375);
PAINT GREEN (-852 4375);
DISPLAY INVISIBLE (-852 4375);
FORCEADD VCC_CORE..1
(-3325 2250);
FORCEPROP 3 LASTPIN (-3325 2200) SIG_NAME P3V3_AUX\g
J 0
(-3315 2210);
DISPLAY 0.659574 (-3315 2210);
PAINT MONO (-3315 2210);
DISPLAY INVISIBLE (-3315 2210);
FORCEPROP 1 LAST HDL_POWER P3V3_AUX
J 1
(-3325 2300);
DISPLAY 1.148936 (-3325 2300);
PAINT GREEN (-3325 2300);
FORCEPROP 2 LAST CDS_LIB logical_power
J 0
(-3325 2250);
PAINT MONO (-3325 2250);
DISPLAY INVISIBLE (-3325 2250);
FORCEPROP 1 LAST PATH I12
J 0
(-3275 2275);
DISPLAY 0.872340 (-3275 2275);
PAINT AQUA (-3275 2275);
DISPLAY INVISIBLE (-3275 2275);
FORCEADD UNIVERSAL_GND..1
(875 125);
FORCEPROP 3 LASTPIN (875 175) SIG_NAME GND\g
J 0
(885 185);
DISPLAY 0.659574 (885 185);
PAINT MONO (885 185);
DISPLAY INVISIBLE (885 185);
FORCEPROP 1 LAST PATH I120
J 0
(950 125);
DISPLAY 0.872340 (950 125);
PAINT AQUA (950 125);
DISPLAY INVISIBLE (950 125);
FORCEPROP 1 LAST HDL_POWER GND
J 1
(900 50);
DISPLAY 0.872340 (900 50);
PAINT GREEN (900 50);
DISPLAY INVISIBLE (900 50);
FORCEPROP 2 LAST CDS_LIB logical_power
J 0
(875 125);
PAINT MONO (875 125);
DISPLAY INVISIBLE (875 125);
FORCEADD UNIVERSAL_GND..1
(2500 125);
FORCEPROP 3 LASTPIN (2500 175) SIG_NAME GND\g
J 0
(2510 185);
DISPLAY 0.659574 (2510 185);
PAINT MONO (2510 185);
DISPLAY INVISIBLE (2510 185);
FORCEPROP 1 LAST PATH I121
J 0
(2575 125);
DISPLAY 0.872340 (2575 125);
PAINT AQUA (2575 125);
DISPLAY INVISIBLE (2575 125);
FORCEPROP 1 LAST HDL_POWER GND
J 1
(2525 50);
DISPLAY 0.872340 (2525 50);
PAINT GREEN (2525 50);
DISPLAY INVISIBLE (2525 50);
FORCEPROP 2 LAST CDS_LIB logical_power
J 0
(2500 125);
PAINT MONO (2500 125);
DISPLAY INVISIBLE (2500 125);
FORCEADD Q_CAP..1
(875 500);
FORCEPROP 1 LAST PART_NUMBER CH5221MEB00
J 0
(925 350);
DISPLAY 0.978723 (925 350);
DISPLAY INVISIBLE (925 350);
FORCEPROP 1 LAST VOLTAGE 6.3V
J 0
(925 500);
DISPLAY 0.978723 (925 500);
FORCEPROP 1 LAST MATERIAL X6S
J 0
(925 400);
DISPLAY 0.978723 (925 400);
FORCEPROP 1 LAST TOLERANCE 20%
J 0
(925 450);
DISPLAY 0.978723 (925 450);
FORCEPROP 1 LAST VALUE 2.2UF
J 0
(925 550);
DISPLAY 0.978723 (925 550);
FORCEPROP 1 LAST PACK_TYPE C0402
J 0
(925 300);
DISPLAY 0.978723 (925 300);
FORCEPROP 1 LAST $LOCATION C90
J 0
(925 600);
DISPLAY 0.978723 (925 600);
FORCEPROP 1 LASTPIN (875 600) $PN 1
J 0
(885 580);
DISPLAY 0.787234 (885 580);
FORCEPROP 1 LASTPIN (875 400) $PN 2
J 0
(885 380);
DISPLAY 0.787234 (885 380);
FORCEPROP 2 LAST CDS_LIB pure_quanta
J 0
(875 500);
PAINT MONO (875 500);
DISPLAY INVISIBLE (875 500);
FORCEPROP 1 LAST PATH I122
J 0
(925 650);
DISPLAY 0.978723 (925 650);
PAINT WHITE (925 650);
DISPLAY INVISIBLE (925 650);
FORCEPROP 1 LAST $LOCATION C90
J 0
(925 700);
DISPLAY 1.021277 (925 700);
DISPLAY INVISIBLE (925 700);
FORCEPROP 2 LAST CDS_LOCATION C90
J 0
(925 700);
DISPLAY 1.021277 (925 700);
DISPLAY INVISIBLE (925 700);
FORCEPROP 2 LAST $SEC 1
J 0
(925 700);
DISPLAY 0.680851 (925 700);
PAINT MONO (925 700);
DISPLAY INVISIBLE (925 700);
FORCEPROP 2 LAST CDS_SEC 1
J 0
(925 700);
DISPLAY 1.021277 (925 700);
DISPLAY INVISIBLE (925 700);
FORCEADD VCC_CORE..1
(875 825);
FORCEPROP 3 LASTPIN (875 775) SIG_NAME P3V3_AUX\g
J 0
(885 785);
DISPLAY 0.659574 (885 785);
PAINT MONO (885 785);
DISPLAY INVISIBLE (885 785);
FORCEPROP 1 LAST HDL_POWER P3V3_AUX
J 1
(875 875);
DISPLAY 1.148936 (875 875);
PAINT GREEN (875 875);
FORCEPROP 2 LAST CDS_LIB logical_power
J 0
(875 825);
PAINT MONO (875 825);
DISPLAY INVISIBLE (875 825);
FORCEPROP 1 LAST PATH I123
J 0
(925 850);
DISPLAY 0.872340 (925 850);
PAINT AQUA (925 850);
DISPLAY INVISIBLE (925 850);
FORCEADD OFFPAGE..3
(-25 2750);
FORCEPROP 2 LAST $XR1 106 
J 0
(279 2750);
DISPLAY 0.638298 (279 2750);
PAINT MONO (279 2750);
FORCEPROP 2 LAST $XR0 55 
J 0
(189 2750);
DISPLAY 0.638298 (189 2750);
PAINT MONO (189 2750);
FORCEPROP 2 LAST CDS_LIB standard
J 2
(-25 2750);
DISPLAY INVISIBLE (-25 2750);
FORCEPROP 1 LAST OFFPAGE TRUE
J 0
(300 2625);
DISPLAY 0.872340 (300 2625);
DISPLAY INVISIBLE (300 2625);
FORCEPROP 1 LAST COMMENT_BODY TRUE
J 0
(-75 2650);
DISPLAY 0.872340 (-75 2650);
PAINT GREEN (-75 2650);
DISPLAY INVISIBLE (-75 2650);
FORCEPROP 2 LAST PATH I124
J 0
(175 2825);
DISPLAY 1.021277 (175 2825);
DISPLAY INVISIBLE (175 2825);
FORCEADD Q_CAP..1
(1875 500);
FORCEPROP 1 LAST PART_NUMBER CH6103KEA00
J 0
(1925 350);
DISPLAY 0.978723 (1925 350);
DISPLAY INVISIBLE (1925 350);
FORCEPROP 1 LAST VOLTAGE 16V
J 0
(1925 500);
DISPLAY 0.978723 (1925 500);
FORCEPROP 1 LAST PACK_TYPE C0805
J 0
(1925 300);
DISPLAY 0.978723 (1925 300);
FORCEPROP 1 LAST TOLERANCE 10%
J 0
(1925 450);
DISPLAY 0.978723 (1925 450);
FORCEPROP 1 LAST MATERIAL X6S
J 0
(1925 400);
DISPLAY 0.978723 (1925 400);
FORCEPROP 1 LAST VALUE 10UF
J 0
(1925 550);
DISPLAY 0.978723 (1925 550);
FORCEPROP 1 LAST $LOCATION C91
J 0
(1925 600);
DISPLAY 0.978723 (1925 600);
FORCEPROP 1 LASTPIN (1875 600) $PN 1
J 0
(1885 580);
DISPLAY 0.787234 (1885 580);
FORCEPROP 1 LASTPIN (1875 400) $PN 2
J 0
(1885 380);
DISPLAY 0.787234 (1885 380);
FORCEPROP 2 LAST CDS_LIB pure_quanta
J 0
(1875 500);
PAINT MONO (1875 500);
DISPLAY INVISIBLE (1875 500);
FORCEPROP 1 LAST PATH I126
J 0
(1925 650);
DISPLAY 0.978723 (1925 650);
PAINT WHITE (1925 650);
DISPLAY INVISIBLE (1925 650);
FORCEPROP 1 LAST $LOCATION C91
J 0
(1925 700);
DISPLAY 1.021277 (1925 700);
DISPLAY INVISIBLE (1925 700);
FORCEPROP 2 LAST CDS_LOCATION C91
J 0
(1925 700);
DISPLAY 1.021277 (1925 700);
DISPLAY INVISIBLE (1925 700);
FORCEPROP 2 LAST $SEC 1
J 0
(1925 700);
DISPLAY 0.680851 (1925 700);
PAINT MONO (1925 700);
DISPLAY INVISIBLE (1925 700);
FORCEPROP 2 LAST CDS_SEC 1
J 0
(1925 700);
DISPLAY 1.021277 (1925 700);
DISPLAY INVISIBLE (1925 700);
FORCEADD VCC_CORE..1
(1875 825);
FORCEPROP 3 LASTPIN (1875 775) SIG_NAME P12V_S3_AUX_CPU1_NVDIMM\g
J 0
(1885 785);
DISPLAY 0.659574 (1885 785);
PAINT MONO (1885 785);
DISPLAY INVISIBLE (1885 785);
FORCEPROP 1 LAST HDL_POWER P12V_S3_AUX_CPU1_NVDIMM
J 1
(1875 875);
DISPLAY 1.148936 (1875 875);
PAINT GREEN (1875 875);
FORCEPROP 2 LAST CDS_LIB logical_power
J 0
(1875 825);
PAINT MONO (1875 825);
DISPLAY INVISIBLE (1875 825);
FORCEPROP 1 LAST PATH I127
J 0
(1925 850);
DISPLAY 0.872340 (1925 850);
PAINT AQUA (1925 850);
DISPLAY INVISIBLE (1925 850);
FORCEADD Q_CAP..1
(2500 500);
FORCEPROP 1 LAST PART_NUMBER CH6103KEA00
J 0
(2550 350);
DISPLAY 0.978723 (2550 350);
DISPLAY INVISIBLE (2550 350);
FORCEPROP 1 LAST PACK_TYPE C0805
J 0
(2550 300);
DISPLAY 0.978723 (2550 300);
FORCEPROP 1 LAST VALUE 10UF
J 0
(2550 550);
DISPLAY 0.978723 (2550 550);
FORCEPROP 1 LAST TOLERANCE 10%
J 0
(2550 450);
DISPLAY 0.978723 (2550 450);
FORCEPROP 1 LAST VOLTAGE 16V
J 0
(2550 500);
DISPLAY 0.978723 (2550 500);
FORCEPROP 1 LAST MATERIAL X6S
J 0
(2550 400);
DISPLAY 0.978723 (2550 400);
FORCEPROP 1 LAST $LOCATION C92
J 0
(2550 600);
DISPLAY 0.978723 (2550 600);
FORCEPROP 1 LASTPIN (2500 600) $PN 1
J 0
(2510 580);
DISPLAY 0.787234 (2510 580);
FORCEPROP 1 LASTPIN (2500 400) $PN 2
J 0
(2510 380);
DISPLAY 0.787234 (2510 380);
FORCEPROP 2 LAST CDS_LIB pure_quanta
J 0
(2500 500);
PAINT MONO (2500 500);
DISPLAY INVISIBLE (2500 500);
FORCEPROP 1 LAST PATH I128
J 0
(2550 650);
DISPLAY 0.978723 (2550 650);
PAINT WHITE (2550 650);
DISPLAY INVISIBLE (2550 650);
FORCEPROP 1 LAST $LOCATION C92
J 0
(2550 700);
DISPLAY 1.021277 (2550 700);
DISPLAY INVISIBLE (2550 700);
FORCEPROP 2 LAST CDS_LOCATION C92
J 0
(2550 700);
DISPLAY 1.021277 (2550 700);
DISPLAY INVISIBLE (2550 700);
FORCEPROP 2 LAST $SEC 1
J 0
(2550 700);
DISPLAY 0.680851 (2550 700);
PAINT MONO (2550 700);
DISPLAY INVISIBLE (2550 700);
FORCEPROP 2 LAST CDS_SEC 1
J 0
(2550 700);
DISPLAY 1.021277 (2550 700);
DISPLAY INVISIBLE (2550 700);
FORCEADD TAP..1
(1900 2425);
FORCEPROP 3 LASTPIN (1850 2425) SIG_NAME M_E_CPU1_SB_DQS_DP<0>
J 0
(1860 2435);
DISPLAY 0.659574 (1860 2435);
PAINT MONO (1860 2435);
DISPLAY INVISIBLE (1860 2435);
FORCEPROP 1 LASTPIN (1850 2425) BN 0
J 0
(1838 2433);
DISPLAY 0.680851 (1838 2433);
PAINT GREEN (1838 2433);
FORCEPROP 2 LAST CDS_LIB standard
J 0
(1900 2425);
PAINT MONO (1900 2425);
DISPLAY INVISIBLE (1900 2425);
FORCEPROP 1 LAST BODY_TYPE PLUMBING
J 0
(1900 2475);
DISPLAY 0.872340 (1900 2475);
PAINT GREEN (1900 2475);
DISPLAY INVISIBLE (1900 2475);
FORCEPROP 1 LAST HDL_TAP TRUE
J 0
(2225 2300);
DISPLAY 0.872340 (2225 2300);
DISPLAY INVISIBLE (2225 2300);
FORCEPROP 1 LAST PATH I129
J 0
(1898 2425);
DISPLAY 0.872340 (1898 2425);
PAINT GREEN (1898 2425);
DISPLAY INVISIBLE (1898 2425);
FORCEADD OFFPAGE..3
R 2
(-3425 2550);
FORCEPROP 2 LAST $XR1 106 
J 0
(-3794 2550);
DISPLAY 0.638298 (-3794 2550);
PAINT MONO (-3794 2550);
FORCEPROP 2 LAST $XR0 55 
J 0
(-3674 2550);
DISPLAY 0.638298 (-3674 2550);
PAINT MONO (-3674 2550);
FORCEPROP 2 LAST CDS_LIB standard
J 0
(-3425 2550);
PAINT MONO (-3425 2550);
DISPLAY INVISIBLE (-3425 2550);
FORCEPROP 1 LAST OFFPAGE TRUE
J 2
(-3750 2425);
DISPLAY 0.872340 (-3750 2425);
DISPLAY INVISIBLE (-3750 2425);
FORCEPROP 1 LAST COMMENT_BODY TRUE
J 2
(-3375 2450);
DISPLAY 0.872340 (-3375 2450);
PAINT GREEN (-3375 2450);
DISPLAY INVISIBLE (-3375 2450);
FORCEPROP 2 LAST PATH I13
J 0
(-3375 2625);
DISPLAY 1.021277 (-3375 2625);
DISPLAY INVISIBLE (-3375 2625);
FORCEADD TAP..1
(1900 2525);
FORCEPROP 3 LASTPIN (1850 2525) SIG_NAME M_E_CPU1_SB_DQS_DP<1>
J 0
(1860 2535);
DISPLAY 0.659574 (1860 2535);
PAINT MONO (1860 2535);
DISPLAY INVISIBLE (1860 2535);
FORCEPROP 1 LASTPIN (1850 2525) BN 1
J 0
(1838 2533);
DISPLAY 0.680851 (1838 2533);
PAINT GREEN (1838 2533);
FORCEPROP 2 LAST CDS_LIB standard
J 0
(1900 2525);
DISPLAY INVISIBLE (1900 2525);
FORCEPROP 1 LAST BODY_TYPE PLUMBING
J 0
(1900 2575);
DISPLAY 0.872340 (1900 2575);
PAINT GREEN (1900 2575);
DISPLAY INVISIBLE (1900 2575);
FORCEPROP 1 LAST HDL_TAP TRUE
J 0
(2225 2400);
DISPLAY 0.872340 (2225 2400);
DISPLAY INVISIBLE (2225 2400);
FORCEPROP 1 LAST PATH I130
J 0
(1898 2525);
DISPLAY 0.872340 (1898 2525);
PAINT GREEN (1898 2525);
DISPLAY INVISIBLE (1898 2525);
FORCEADD TAP..1
(1900 2725);
FORCEPROP 3 LASTPIN (1850 2725) SIG_NAME M_E_CPU1_SB_DQS_DP<3>
J 0
(1860 2735);
DISPLAY 0.659574 (1860 2735);
PAINT MONO (1860 2735);
DISPLAY INVISIBLE (1860 2735);
FORCEPROP 1 LASTPIN (1850 2725) BN 3
J 0
(1838 2733);
DISPLAY 0.680851 (1838 2733);
PAINT GREEN (1838 2733);
FORCEPROP 2 LAST CDS_LIB standard
J 0
(1900 2725);
PAINT MONO (1900 2725);
DISPLAY INVISIBLE (1900 2725);
FORCEPROP 1 LAST BODY_TYPE PLUMBING
J 0
(1900 2775);
DISPLAY 0.872340 (1900 2775);
PAINT GREEN (1900 2775);
DISPLAY INVISIBLE (1900 2775);
FORCEPROP 1 LAST HDL_TAP TRUE
J 0
(2225 2600);
DISPLAY 0.872340 (2225 2600);
DISPLAY INVISIBLE (2225 2600);
FORCEPROP 1 LAST PATH I131
J 0
(1898 2725);
DISPLAY 0.872340 (1898 2725);
PAINT GREEN (1898 2725);
DISPLAY INVISIBLE (1898 2725);
FORCEADD TAP..1
(1900 2625);
FORCEPROP 3 LASTPIN (1850 2625) SIG_NAME M_E_CPU1_SB_DQS_DP<2>
J 0
(1860 2635);
DISPLAY 0.659574 (1860 2635);
PAINT MONO (1860 2635);
DISPLAY INVISIBLE (1860 2635);
FORCEPROP 1 LASTPIN (1850 2625) BN 2
J 0
(1838 2633);
DISPLAY 0.680851 (1838 2633);
PAINT GREEN (1838 2633);
FORCEPROP 2 LAST CDS_LIB standard
J 0
(1900 2625);
DISPLAY INVISIBLE (1900 2625);
FORCEPROP 1 LAST BODY_TYPE PLUMBING
J 0
(1900 2675);
DISPLAY 0.872340 (1900 2675);
PAINT GREEN (1900 2675);
DISPLAY INVISIBLE (1900 2675);
FORCEPROP 1 LAST HDL_TAP TRUE
J 0
(2225 2500);
DISPLAY 0.872340 (2225 2500);
DISPLAY INVISIBLE (2225 2500);
FORCEPROP 1 LAST PATH I132
J 0
(1898 2625);
DISPLAY 0.872340 (1898 2625);
PAINT GREEN (1898 2625);
DISPLAY INVISIBLE (1898 2625);
FORCEADD TAP..1
(1900 2825);
FORCEPROP 3 LASTPIN (1850 2825) SIG_NAME M_E_CPU1_SB_DQS_DP<4>
J 0
(1860 2835);
DISPLAY 0.659574 (1860 2835);
PAINT MONO (1860 2835);
DISPLAY INVISIBLE (1860 2835);
FORCEPROP 1 LASTPIN (1850 2825) BN 4
J 0
(1838 2833);
DISPLAY 0.680851 (1838 2833);
PAINT GREEN (1838 2833);
FORCEPROP 2 LAST CDS_LIB standard
J 0
(1900 2825);
PAINT MONO (1900 2825);
DISPLAY INVISIBLE (1900 2825);
FORCEPROP 1 LAST BODY_TYPE PLUMBING
J 0
(1900 2875);
DISPLAY 0.872340 (1900 2875);
PAINT GREEN (1900 2875);
DISPLAY INVISIBLE (1900 2875);
FORCEPROP 1 LAST HDL_TAP TRUE
J 0
(2225 2700);
DISPLAY 0.872340 (2225 2700);
DISPLAY INVISIBLE (2225 2700);
FORCEPROP 1 LAST PATH I133
J 0
(1898 2825);
DISPLAY 0.872340 (1898 2825);
PAINT GREEN (1898 2825);
DISPLAY INVISIBLE (1898 2825);
FORCEADD TAP..1
(1900 2925);
FORCEPROP 3 LASTPIN (1850 2925) SIG_NAME M_E_CPU1_SB_DQS_DP<5>
J 0
(1860 2935);
DISPLAY 0.659574 (1860 2935);
PAINT MONO (1860 2935);
DISPLAY INVISIBLE (1860 2935);
FORCEPROP 1 LASTPIN (1850 2925) BN 5
J 0
(1838 2933);
DISPLAY 0.680851 (1838 2933);
PAINT GREEN (1838 2933);
FORCEPROP 2 LAST CDS_LIB standard
J 0
(1900 2925);
DISPLAY INVISIBLE (1900 2925);
FORCEPROP 1 LAST BODY_TYPE PLUMBING
J 0
(1900 2975);
DISPLAY 0.872340 (1900 2975);
PAINT GREEN (1900 2975);
DISPLAY INVISIBLE (1900 2975);
FORCEPROP 1 LAST HDL_TAP TRUE
J 0
(2225 2800);
DISPLAY 0.872340 (2225 2800);
DISPLAY INVISIBLE (2225 2800);
FORCEPROP 1 LAST PATH I134
J 0
(1898 2925);
DISPLAY 0.872340 (1898 2925);
PAINT GREEN (1898 2925);
DISPLAY INVISIBLE (1898 2925);
FORCEADD TAP..1
(1900 3025);
FORCEPROP 3 LASTPIN (1850 3025) SIG_NAME M_E_CPU1_SB_DQS_DP<6>
J 0
(1860 3035);
DISPLAY 0.659574 (1860 3035);
PAINT MONO (1860 3035);
DISPLAY INVISIBLE (1860 3035);
FORCEPROP 1 LASTPIN (1850 3025) BN 6
J 0
(1838 3033);
DISPLAY 0.680851 (1838 3033);
PAINT GREEN (1838 3033);
FORCEPROP 2 LAST CDS_LIB standard
J 0
(1900 3025);
DISPLAY INVISIBLE (1900 3025);
FORCEPROP 1 LAST BODY_TYPE PLUMBING
J 0
(1900 3075);
DISPLAY 0.872340 (1900 3075);
PAINT GREEN (1900 3075);
DISPLAY INVISIBLE (1900 3075);
FORCEPROP 1 LAST HDL_TAP TRUE
J 0
(2225 2900);
DISPLAY 0.872340 (2225 2900);
DISPLAY INVISIBLE (2225 2900);
FORCEPROP 1 LAST PATH I135
J 0
(1898 3025);
DISPLAY 0.872340 (1898 3025);
PAINT GREEN (1898 3025);
DISPLAY INVISIBLE (1898 3025);
FORCEADD TAP..1
(1900 3125);
FORCEPROP 3 LASTPIN (1850 3125) SIG_NAME M_E_CPU1_SB_DQS_DP<7>
J 0
(1860 3135);
DISPLAY 0.659574 (1860 3135);
PAINT MONO (1860 3135);
DISPLAY INVISIBLE (1860 3135);
FORCEPROP 1 LASTPIN (1850 3125) BN 7
J 0
(1838 3133);
DISPLAY 0.680851 (1838 3133);
PAINT GREEN (1838 3133);
FORCEPROP 2 LAST CDS_LIB standard
J 0
(1900 3125);
DISPLAY INVISIBLE (1900 3125);
FORCEPROP 1 LAST BODY_TYPE PLUMBING
J 0
(1900 3175);
DISPLAY 0.872340 (1900 3175);
PAINT GREEN (1900 3175);
DISPLAY INVISIBLE (1900 3175);
FORCEPROP 1 LAST HDL_TAP TRUE
J 0
(2225 3000);
DISPLAY 0.872340 (2225 3000);
DISPLAY INVISIBLE (2225 3000);
FORCEPROP 1 LAST PATH I136
J 0
(1898 3125);
DISPLAY 0.872340 (1898 3125);
PAINT GREEN (1898 3125);
DISPLAY INVISIBLE (1898 3125);
FORCEADD TAP..1
(1900 3225);
FORCEPROP 3 LASTPIN (1850 3225) SIG_NAME M_E_CPU1_SB_DQS_DP<8>
J 0
(1860 3235);
DISPLAY 0.659574 (1860 3235);
PAINT MONO (1860 3235);
DISPLAY INVISIBLE (1860 3235);
FORCEPROP 1 LASTPIN (1850 3225) BN 8
J 0
(1838 3233);
DISPLAY 0.680851 (1838 3233);
PAINT GREEN (1838 3233);
FORCEPROP 2 LAST CDS_LIB standard
J 0
(1900 3225);
DISPLAY INVISIBLE (1900 3225);
FORCEPROP 1 LAST BODY_TYPE PLUMBING
J 0
(1900 3275);
DISPLAY 0.872340 (1900 3275);
PAINT GREEN (1900 3275);
DISPLAY INVISIBLE (1900 3275);
FORCEPROP 1 LAST HDL_TAP TRUE
J 0
(2225 3100);
DISPLAY 0.872340 (2225 3100);
DISPLAY INVISIBLE (2225 3100);
FORCEPROP 1 LAST PATH I137
J 0
(1898 3225);
DISPLAY 0.872340 (1898 3225);
PAINT GREEN (1898 3225);
DISPLAY INVISIBLE (1898 3225);
FORCEADD TAP..1
(2075 2375);
FORCEPROP 3 LASTPIN (2025 2375) SIG_NAME M_E_CPU1_SB_DQS_DN<0>
J 0
(2035 2385);
DISPLAY 0.659574 (2035 2385);
PAINT MONO (2035 2385);
DISPLAY INVISIBLE (2035 2385);
FORCEPROP 1 LASTPIN (2025 2375) BN 0
J 0
(2013 2383);
DISPLAY 0.680851 (2013 2383);
PAINT GREEN (2013 2383);
FORCEPROP 2 LAST CDS_LIB standard
J 0
(2075 2375);
PAINT MONO (2075 2375);
DISPLAY INVISIBLE (2075 2375);
FORCEPROP 1 LAST BODY_TYPE PLUMBING
J 0
(2075 2425);
DISPLAY 0.872340 (2075 2425);
PAINT GREEN (2075 2425);
DISPLAY INVISIBLE (2075 2425);
FORCEPROP 1 LAST HDL_TAP TRUE
J 0
(2400 2250);
DISPLAY 0.872340 (2400 2250);
DISPLAY INVISIBLE (2400 2250);
FORCEPROP 1 LAST PATH I138
J 0
(2073 2375);
DISPLAY 0.872340 (2073 2375);
PAINT GREEN (2073 2375);
DISPLAY INVISIBLE (2073 2375);
FORCEADD TAP..1
(2075 2475);
FORCEPROP 3 LASTPIN (2025 2475) SIG_NAME M_E_CPU1_SB_DQS_DN<1>
J 0
(2035 2485);
DISPLAY 0.659574 (2035 2485);
PAINT MONO (2035 2485);
DISPLAY INVISIBLE (2035 2485);
FORCEPROP 1 LASTPIN (2025 2475) BN 1
J 0
(2013 2483);
DISPLAY 0.680851 (2013 2483);
PAINT GREEN (2013 2483);
FORCEPROP 2 LAST CDS_LIB standard
J 0
(2075 2475);
DISPLAY INVISIBLE (2075 2475);
FORCEPROP 1 LAST BODY_TYPE PLUMBING
J 0
(2075 2525);
DISPLAY 0.872340 (2075 2525);
PAINT GREEN (2075 2525);
DISPLAY INVISIBLE (2075 2525);
FORCEPROP 1 LAST HDL_TAP TRUE
J 0
(2400 2350);
DISPLAY 0.872340 (2400 2350);
DISPLAY INVISIBLE (2400 2350);
FORCEPROP 1 LAST PATH I139
J 0
(2073 2475);
DISPLAY 0.872340 (2073 2475);
PAINT GREEN (2073 2475);
DISPLAY INVISIBLE (2073 2475);
FORCEADD OFFPAGE..3
R 2
(-3425 3000);
FORCEPROP 2 LAST $XR1 106 
J 0
(-3794 3000);
DISPLAY 0.638298 (-3794 3000);
PAINT MONO (-3794 3000);
FORCEPROP 2 LAST $XR0 55 
J 0
(-3674 3000);
DISPLAY 0.638298 (-3674 3000);
PAINT MONO (-3674 3000);
FORCEPROP 2 LAST CDS_LIB standard
J 0
(-3425 3000);
PAINT MONO (-3425 3000);
DISPLAY INVISIBLE (-3425 3000);
FORCEPROP 1 LAST OFFPAGE TRUE
J 2
(-3750 2875);
DISPLAY 0.872340 (-3750 2875);
DISPLAY INVISIBLE (-3750 2875);
FORCEPROP 1 LAST COMMENT_BODY TRUE
J 2
(-3375 2900);
DISPLAY 0.872340 (-3375 2900);
PAINT GREEN (-3375 2900);
DISPLAY INVISIBLE (-3375 2900);
FORCEPROP 2 LAST PATH I14
J 0
(-3375 3075);
DISPLAY 1.021277 (-3375 3075);
DISPLAY INVISIBLE (-3375 3075);
FORCEADD TAP..1
(2075 2675);
FORCEPROP 3 LASTPIN (2025 2675) SIG_NAME M_E_CPU1_SB_DQS_DN<3>
J 0
(2035 2685);
DISPLAY 0.659574 (2035 2685);
PAINT MONO (2035 2685);
DISPLAY INVISIBLE (2035 2685);
FORCEPROP 1 LASTPIN (2025 2675) BN 3
J 0
(2013 2683);
DISPLAY 0.680851 (2013 2683);
PAINT GREEN (2013 2683);
FORCEPROP 2 LAST CDS_LIB standard
J 0
(2075 2675);
PAINT MONO (2075 2675);
DISPLAY INVISIBLE (2075 2675);
FORCEPROP 1 LAST BODY_TYPE PLUMBING
J 0
(2075 2725);
DISPLAY 0.872340 (2075 2725);
PAINT GREEN (2075 2725);
DISPLAY INVISIBLE (2075 2725);
FORCEPROP 1 LAST HDL_TAP TRUE
J 0
(2400 2550);
DISPLAY 0.872340 (2400 2550);
DISPLAY INVISIBLE (2400 2550);
FORCEPROP 1 LAST PATH I140
J 0
(2073 2675);
DISPLAY 0.872340 (2073 2675);
PAINT GREEN (2073 2675);
DISPLAY INVISIBLE (2073 2675);
FORCEADD TAP..1
(2075 2575);
FORCEPROP 3 LASTPIN (2025 2575) SIG_NAME M_E_CPU1_SB_DQS_DN<2>
J 0
(2035 2585);
DISPLAY 0.659574 (2035 2585);
PAINT MONO (2035 2585);
DISPLAY INVISIBLE (2035 2585);
FORCEPROP 1 LASTPIN (2025 2575) BN 2
J 0
(2013 2583);
DISPLAY 0.680851 (2013 2583);
PAINT GREEN (2013 2583);
FORCEPROP 2 LAST CDS_LIB standard
J 0
(2075 2575);
DISPLAY INVISIBLE (2075 2575);
FORCEPROP 1 LAST BODY_TYPE PLUMBING
J 0
(2075 2625);
DISPLAY 0.872340 (2075 2625);
PAINT GREEN (2075 2625);
DISPLAY INVISIBLE (2075 2625);
FORCEPROP 1 LAST HDL_TAP TRUE
J 0
(2400 2450);
DISPLAY 0.872340 (2400 2450);
DISPLAY INVISIBLE (2400 2450);
FORCEPROP 1 LAST PATH I141
J 0
(2073 2575);
DISPLAY 0.872340 (2073 2575);
PAINT GREEN (2073 2575);
DISPLAY INVISIBLE (2073 2575);
FORCEADD TAP..1
(2075 2775);
FORCEPROP 3 LASTPIN (2025 2775) SIG_NAME M_E_CPU1_SB_DQS_DN<4>
J 0
(2035 2785);
DISPLAY 0.659574 (2035 2785);
PAINT MONO (2035 2785);
DISPLAY INVISIBLE (2035 2785);
FORCEPROP 1 LASTPIN (2025 2775) BN 4
J 0
(2013 2783);
DISPLAY 0.680851 (2013 2783);
PAINT GREEN (2013 2783);
FORCEPROP 2 LAST CDS_LIB standard
J 0
(2075 2775);
PAINT MONO (2075 2775);
DISPLAY INVISIBLE (2075 2775);
FORCEPROP 1 LAST BODY_TYPE PLUMBING
J 0
(2075 2825);
DISPLAY 0.872340 (2075 2825);
PAINT GREEN (2075 2825);
DISPLAY INVISIBLE (2075 2825);
FORCEPROP 1 LAST HDL_TAP TRUE
J 0
(2400 2650);
DISPLAY 0.872340 (2400 2650);
DISPLAY INVISIBLE (2400 2650);
FORCEPROP 1 LAST PATH I142
J 0
(2073 2775);
DISPLAY 0.872340 (2073 2775);
PAINT GREEN (2073 2775);
DISPLAY INVISIBLE (2073 2775);
FORCEADD TAP..1
(2075 2875);
FORCEPROP 3 LASTPIN (2025 2875) SIG_NAME M_E_CPU1_SB_DQS_DN<5>
J 0
(2035 2885);
DISPLAY 0.659574 (2035 2885);
PAINT MONO (2035 2885);
DISPLAY INVISIBLE (2035 2885);
FORCEPROP 1 LASTPIN (2025 2875) BN 5
J 0
(2013 2883);
DISPLAY 0.680851 (2013 2883);
PAINT GREEN (2013 2883);
FORCEPROP 2 LAST CDS_LIB standard
J 0
(2075 2875);
DISPLAY INVISIBLE (2075 2875);
FORCEPROP 1 LAST BODY_TYPE PLUMBING
J 0
(2075 2925);
DISPLAY 0.872340 (2075 2925);
PAINT GREEN (2075 2925);
DISPLAY INVISIBLE (2075 2925);
FORCEPROP 1 LAST HDL_TAP TRUE
J 0
(2400 2750);
DISPLAY 0.872340 (2400 2750);
DISPLAY INVISIBLE (2400 2750);
FORCEPROP 1 LAST PATH I143
J 0
(2073 2875);
DISPLAY 0.872340 (2073 2875);
PAINT GREEN (2073 2875);
DISPLAY INVISIBLE (2073 2875);
FORCEADD TAP..1
(2075 2975);
FORCEPROP 3 LASTPIN (2025 2975) SIG_NAME M_E_CPU1_SB_DQS_DN<6>
J 0
(2035 2985);
DISPLAY 0.659574 (2035 2985);
PAINT MONO (2035 2985);
DISPLAY INVISIBLE (2035 2985);
FORCEPROP 1 LASTPIN (2025 2975) BN 6
J 0
(2013 2983);
DISPLAY 0.680851 (2013 2983);
PAINT GREEN (2013 2983);
FORCEPROP 2 LAST CDS_LIB standard
J 0
(2075 2975);
DISPLAY INVISIBLE (2075 2975);
FORCEPROP 1 LAST BODY_TYPE PLUMBING
J 0
(2075 3025);
DISPLAY 0.872340 (2075 3025);
PAINT GREEN (2075 3025);
DISPLAY INVISIBLE (2075 3025);
FORCEPROP 1 LAST HDL_TAP TRUE
J 0
(2400 2850);
DISPLAY 0.872340 (2400 2850);
DISPLAY INVISIBLE (2400 2850);
FORCEPROP 1 LAST PATH I144
J 0
(2073 2975);
DISPLAY 0.872340 (2073 2975);
PAINT GREEN (2073 2975);
DISPLAY INVISIBLE (2073 2975);
FORCEADD TAP..1
(2075 3175);
FORCEPROP 3 LASTPIN (2025 3175) SIG_NAME M_E_CPU1_SB_DQS_DN<8>
J 0
(2035 3185);
DISPLAY 0.659574 (2035 3185);
PAINT MONO (2035 3185);
DISPLAY INVISIBLE (2035 3185);
FORCEPROP 1 LASTPIN (2025 3175) BN 8
J 0
(2013 3183);
DISPLAY 0.680851 (2013 3183);
PAINT GREEN (2013 3183);
FORCEPROP 2 LAST CDS_LIB standard
J 0
(2075 3175);
DISPLAY INVISIBLE (2075 3175);
FORCEPROP 1 LAST BODY_TYPE PLUMBING
J 0
(2075 3225);
DISPLAY 0.872340 (2075 3225);
PAINT GREEN (2075 3225);
DISPLAY INVISIBLE (2075 3225);
FORCEPROP 1 LAST HDL_TAP TRUE
J 0
(2400 3050);
DISPLAY 0.872340 (2400 3050);
DISPLAY INVISIBLE (2400 3050);
FORCEPROP 1 LAST PATH I145
J 0
(2073 3175);
DISPLAY 0.872340 (2073 3175);
PAINT GREEN (2073 3175);
DISPLAY INVISIBLE (2073 3175);
FORCEADD TAP..1
(2075 3075);
FORCEPROP 3 LASTPIN (2025 3075) SIG_NAME M_E_CPU1_SB_DQS_DN<7>
J 0
(2035 3085);
DISPLAY 0.659574 (2035 3085);
PAINT MONO (2035 3085);
DISPLAY INVISIBLE (2035 3085);
FORCEPROP 1 LASTPIN (2025 3075) BN 7
J 0
(2013 3083);
DISPLAY 0.680851 (2013 3083);
PAINT GREEN (2013 3083);
FORCEPROP 2 LAST CDS_LIB standard
J 0
(2075 3075);
DISPLAY INVISIBLE (2075 3075);
FORCEPROP 1 LAST BODY_TYPE PLUMBING
J 0
(2075 3125);
DISPLAY 0.872340 (2075 3125);
PAINT GREEN (2075 3125);
DISPLAY INVISIBLE (2075 3125);
FORCEPROP 1 LAST HDL_TAP TRUE
J 0
(2400 2950);
DISPLAY 0.872340 (2400 2950);
DISPLAY INVISIBLE (2400 2950);
FORCEPROP 1 LAST PATH I146
J 0
(2073 3075);
DISPLAY 0.872340 (2073 3075);
PAINT GREEN (2073 3075);
DISPLAY INVISIBLE (2073 3075);
FORCEADD TAP..1
(2075 3275);
FORCEPROP 3 LASTPIN (2025 3275) SIG_NAME M_E_CPU1_SB_DQS_DN<9>
J 0
(2035 3285);
DISPLAY 0.659574 (2035 3285);
PAINT MONO (2035 3285);
DISPLAY INVISIBLE (2035 3285);
FORCEPROP 1 LASTPIN (2025 3275) BN 9
J 0
(2013 3283);
DISPLAY 0.680851 (2013 3283);
PAINT GREEN (2013 3283);
FORCEPROP 2 LAST CDS_LIB standard
J 0
(2075 3275);
DISPLAY INVISIBLE (2075 3275);
FORCEPROP 1 LAST BODY_TYPE PLUMBING
J 0
(2075 3325);
DISPLAY 0.872340 (2075 3325);
PAINT GREEN (2075 3325);
DISPLAY INVISIBLE (2075 3325);
FORCEPROP 1 LAST HDL_TAP TRUE
J 0
(2400 3150);
DISPLAY 0.872340 (2400 3150);
DISPLAY INVISIBLE (2400 3150);
FORCEPROP 1 LAST PATH I147
J 0
(2073 3275);
DISPLAY 0.872340 (2073 3275);
PAINT GREEN (2073 3275);
DISPLAY INVISIBLE (2073 3275);
FORCEADD TAP..1
(1900 3475);
FORCEPROP 3 LASTPIN (1850 3475) SIG_NAME M_E_CPU1_SA_DQS_DP<0>
J 0
(1860 3485);
DISPLAY 0.659574 (1860 3485);
PAINT MONO (1860 3485);
DISPLAY INVISIBLE (1860 3485);
FORCEPROP 1 LASTPIN (1850 3475) BN 0
J 0
(1838 3483);
DISPLAY 0.680851 (1838 3483);
PAINT GREEN (1838 3483);
FORCEPROP 2 LAST CDS_LIB standard
J 0
(1900 3475);
PAINT MONO (1900 3475);
DISPLAY INVISIBLE (1900 3475);
FORCEPROP 1 LAST BODY_TYPE PLUMBING
J 0
(1900 3525);
DISPLAY 0.872340 (1900 3525);
PAINT GREEN (1900 3525);
DISPLAY INVISIBLE (1900 3525);
FORCEPROP 1 LAST HDL_TAP TRUE
J 0
(2225 3350);
DISPLAY 0.872340 (2225 3350);
DISPLAY INVISIBLE (2225 3350);
FORCEPROP 1 LAST PATH I148
J 0
(1898 3475);
DISPLAY 0.872340 (1898 3475);
PAINT GREEN (1898 3475);
DISPLAY INVISIBLE (1898 3475);
FORCEADD TAP..1
(1900 3325);
FORCEPROP 3 LASTPIN (1850 3325) SIG_NAME M_E_CPU1_SB_DQS_DP<9>
J 0
(1860 3335);
DISPLAY 0.659574 (1860 3335);
PAINT MONO (1860 3335);
DISPLAY INVISIBLE (1860 3335);
FORCEPROP 1 LASTPIN (1850 3325) BN 9
J 0
(1838 3333);
DISPLAY 0.680851 (1838 3333);
PAINT GREEN (1838 3333);
FORCEPROP 2 LAST CDS_LIB standard
J 0
(1900 3325);
DISPLAY INVISIBLE (1900 3325);
FORCEPROP 1 LAST BODY_TYPE PLUMBING
J 0
(1900 3375);
DISPLAY 0.872340 (1900 3375);
PAINT GREEN (1900 3375);
DISPLAY INVISIBLE (1900 3375);
FORCEPROP 1 LAST HDL_TAP TRUE
J 0
(2225 3200);
DISPLAY 0.872340 (2225 3200);
DISPLAY INVISIBLE (2225 3200);
FORCEPROP 1 LAST PATH I149
J 0
(1898 3325);
DISPLAY 0.872340 (1898 3325);
PAINT GREEN (1898 3325);
DISPLAY INVISIBLE (1898 3325);
FORCEADD OFFPAGE..1
(-3425 3075);
FORCEPROP 2 LAST $XR0 55 
J 0
(-3646 3075);
DISPLAY 0.638298 (-3646 3075);
PAINT MONO (-3646 3075);
FORCEPROP 2 LAST CDS_LIB standard
J 0
(-3425 3075);
PAINT MONO (-3425 3075);
DISPLAY INVISIBLE (-3425 3075);
FORCEPROP 1 LAST OFFPAGE TRUE
J 0
(-3100 2950);
DISPLAY 0.872340 (-3100 2950);
DISPLAY INVISIBLE (-3100 2950);
FORCEPROP 1 LAST COMMENT_BODY TRUE
J 0
(-3300 2975);
DISPLAY 0.872340 (-3300 2975);
PAINT GREEN (-3300 2975);
DISPLAY INVISIBLE (-3300 2975);
FORCEPROP 2 LAST PATH I15
J 0
(-3375 3150);
DISPLAY 1.021277 (-3375 3150);
DISPLAY INVISIBLE (-3375 3150);
FORCEADD TAP..1
(1900 3575);
FORCEPROP 3 LASTPIN (1850 3575) SIG_NAME M_E_CPU1_SA_DQS_DP<1>
J 0
(1860 3585);
DISPLAY 0.659574 (1860 3585);
PAINT MONO (1860 3585);
DISPLAY INVISIBLE (1860 3585);
FORCEPROP 1 LASTPIN (1850 3575) BN 1
J 0
(1838 3583);
DISPLAY 0.680851 (1838 3583);
PAINT GREEN (1838 3583);
FORCEPROP 2 LAST CDS_LIB standard
J 0
(1900 3575);
DISPLAY INVISIBLE (1900 3575);
FORCEPROP 1 LAST BODY_TYPE PLUMBING
J 0
(1900 3625);
DISPLAY 0.872340 (1900 3625);
PAINT GREEN (1900 3625);
DISPLAY INVISIBLE (1900 3625);
FORCEPROP 1 LAST HDL_TAP TRUE
J 0
(2225 3450);
DISPLAY 0.872340 (2225 3450);
DISPLAY INVISIBLE (2225 3450);
FORCEPROP 1 LAST PATH I150
J 0
(1898 3575);
DISPLAY 0.872340 (1898 3575);
PAINT GREEN (1898 3575);
DISPLAY INVISIBLE (1898 3575);
FORCEADD TAP..1
(1900 3775);
FORCEPROP 3 LASTPIN (1850 3775) SIG_NAME M_E_CPU1_SA_DQS_DP<3>
J 0
(1860 3785);
DISPLAY 0.659574 (1860 3785);
PAINT MONO (1860 3785);
DISPLAY INVISIBLE (1860 3785);
FORCEPROP 1 LASTPIN (1850 3775) BN 3
J 0
(1838 3783);
DISPLAY 0.680851 (1838 3783);
PAINT GREEN (1838 3783);
FORCEPROP 2 LAST CDS_LIB standard
J 0
(1900 3775);
PAINT MONO (1900 3775);
DISPLAY INVISIBLE (1900 3775);
FORCEPROP 1 LAST BODY_TYPE PLUMBING
J 0
(1900 3825);
DISPLAY 0.872340 (1900 3825);
PAINT GREEN (1900 3825);
DISPLAY INVISIBLE (1900 3825);
FORCEPROP 1 LAST HDL_TAP TRUE
J 0
(2225 3650);
DISPLAY 0.872340 (2225 3650);
DISPLAY INVISIBLE (2225 3650);
FORCEPROP 1 LAST PATH I151
J 0
(1898 3775);
DISPLAY 0.872340 (1898 3775);
PAINT GREEN (1898 3775);
DISPLAY INVISIBLE (1898 3775);
FORCEADD TAP..1
(1900 3675);
FORCEPROP 3 LASTPIN (1850 3675) SIG_NAME M_E_CPU1_SA_DQS_DP<2>
J 0
(1860 3685);
DISPLAY 0.659574 (1860 3685);
PAINT MONO (1860 3685);
DISPLAY INVISIBLE (1860 3685);
FORCEPROP 1 LASTPIN (1850 3675) BN 2
J 0
(1838 3683);
DISPLAY 0.680851 (1838 3683);
PAINT GREEN (1838 3683);
FORCEPROP 2 LAST CDS_LIB standard
J 0
(1900 3675);
DISPLAY INVISIBLE (1900 3675);
FORCEPROP 1 LAST BODY_TYPE PLUMBING
J 0
(1900 3725);
DISPLAY 0.872340 (1900 3725);
PAINT GREEN (1900 3725);
DISPLAY INVISIBLE (1900 3725);
FORCEPROP 1 LAST HDL_TAP TRUE
J 0
(2225 3550);
DISPLAY 0.872340 (2225 3550);
DISPLAY INVISIBLE (2225 3550);
FORCEPROP 1 LAST PATH I152
J 0
(1898 3675);
DISPLAY 0.872340 (1898 3675);
PAINT GREEN (1898 3675);
DISPLAY INVISIBLE (1898 3675);
FORCEADD TAP..1
(1900 3875);
FORCEPROP 3 LASTPIN (1850 3875) SIG_NAME M_E_CPU1_SA_DQS_DP<4>
J 0
(1860 3885);
DISPLAY 0.659574 (1860 3885);
PAINT MONO (1860 3885);
DISPLAY INVISIBLE (1860 3885);
FORCEPROP 1 LASTPIN (1850 3875) BN 4
J 0
(1838 3883);
DISPLAY 0.680851 (1838 3883);
PAINT GREEN (1838 3883);
FORCEPROP 2 LAST CDS_LIB standard
J 0
(1900 3875);
PAINT MONO (1900 3875);
DISPLAY INVISIBLE (1900 3875);
FORCEPROP 1 LAST BODY_TYPE PLUMBING
J 0
(1900 3925);
DISPLAY 0.872340 (1900 3925);
PAINT GREEN (1900 3925);
DISPLAY INVISIBLE (1900 3925);
FORCEPROP 1 LAST HDL_TAP TRUE
J 0
(2225 3750);
DISPLAY 0.872340 (2225 3750);
DISPLAY INVISIBLE (2225 3750);
FORCEPROP 1 LAST PATH I153
J 0
(1898 3875);
DISPLAY 0.872340 (1898 3875);
PAINT GREEN (1898 3875);
DISPLAY INVISIBLE (1898 3875);
FORCEADD TAP..1
(1900 3975);
FORCEPROP 3 LASTPIN (1850 3975) SIG_NAME M_E_CPU1_SA_DQS_DP<5>
J 0
(1860 3985);
DISPLAY 0.659574 (1860 3985);
PAINT MONO (1860 3985);
DISPLAY INVISIBLE (1860 3985);
FORCEPROP 1 LASTPIN (1850 3975) BN 5
J 0
(1838 3983);
DISPLAY 0.680851 (1838 3983);
PAINT GREEN (1838 3983);
FORCEPROP 2 LAST CDS_LIB standard
J 0
(1900 3975);
DISPLAY INVISIBLE (1900 3975);
FORCEPROP 1 LAST BODY_TYPE PLUMBING
J 0
(1900 4025);
DISPLAY 0.872340 (1900 4025);
PAINT GREEN (1900 4025);
DISPLAY INVISIBLE (1900 4025);
FORCEPROP 1 LAST HDL_TAP TRUE
J 0
(2225 3850);
DISPLAY 0.872340 (2225 3850);
DISPLAY INVISIBLE (2225 3850);
FORCEPROP 1 LAST PATH I154
J 0
(1898 3975);
DISPLAY 0.872340 (1898 3975);
PAINT GREEN (1898 3975);
DISPLAY INVISIBLE (1898 3975);
FORCEADD TAP..1
(1900 4075);
FORCEPROP 3 LASTPIN (1850 4075) SIG_NAME M_E_CPU1_SA_DQS_DP<6>
J 0
(1860 4085);
DISPLAY 0.659574 (1860 4085);
PAINT MONO (1860 4085);
DISPLAY INVISIBLE (1860 4085);
FORCEPROP 1 LASTPIN (1850 4075) BN 6
J 0
(1838 4083);
DISPLAY 0.680851 (1838 4083);
PAINT GREEN (1838 4083);
FORCEPROP 2 LAST CDS_LIB standard
J 0
(1900 4075);
DISPLAY INVISIBLE (1900 4075);
FORCEPROP 1 LAST BODY_TYPE PLUMBING
J 0
(1900 4125);
DISPLAY 0.872340 (1900 4125);
PAINT GREEN (1900 4125);
DISPLAY INVISIBLE (1900 4125);
FORCEPROP 1 LAST HDL_TAP TRUE
J 0
(2225 3950);
DISPLAY 0.872340 (2225 3950);
DISPLAY INVISIBLE (2225 3950);
FORCEPROP 1 LAST PATH I155
J 0
(1898 4075);
DISPLAY 0.872340 (1898 4075);
PAINT GREEN (1898 4075);
DISPLAY INVISIBLE (1898 4075);
FORCEADD TAP..1
(1900 4275);
FORCEPROP 3 LASTPIN (1850 4275) SIG_NAME M_E_CPU1_SA_DQS_DP<8>
J 0
(1860 4285);
DISPLAY 0.659574 (1860 4285);
PAINT MONO (1860 4285);
DISPLAY INVISIBLE (1860 4285);
FORCEPROP 1 LASTPIN (1850 4275) BN 8
J 0
(1838 4283);
DISPLAY 0.680851 (1838 4283);
PAINT GREEN (1838 4283);
FORCEPROP 2 LAST CDS_LIB standard
J 0
(1900 4275);
DISPLAY INVISIBLE (1900 4275);
FORCEPROP 1 LAST BODY_TYPE PLUMBING
J 0
(1900 4325);
DISPLAY 0.872340 (1900 4325);
PAINT GREEN (1900 4325);
DISPLAY INVISIBLE (1900 4325);
FORCEPROP 1 LAST HDL_TAP TRUE
J 0
(2225 4150);
DISPLAY 0.872340 (2225 4150);
DISPLAY INVISIBLE (2225 4150);
FORCEPROP 1 LAST PATH I156
J 0
(1898 4275);
DISPLAY 0.872340 (1898 4275);
PAINT GREEN (1898 4275);
DISPLAY INVISIBLE (1898 4275);
FORCEADD TAP..1
(1900 4175);
FORCEPROP 3 LASTPIN (1850 4175) SIG_NAME M_E_CPU1_SA_DQS_DP<7>
J 0
(1860 4185);
DISPLAY 0.659574 (1860 4185);
PAINT MONO (1860 4185);
DISPLAY INVISIBLE (1860 4185);
FORCEPROP 1 LASTPIN (1850 4175) BN 7
J 0
(1838 4183);
DISPLAY 0.680851 (1838 4183);
PAINT GREEN (1838 4183);
FORCEPROP 2 LAST CDS_LIB standard
J 0
(1900 4175);
DISPLAY INVISIBLE (1900 4175);
FORCEPROP 1 LAST BODY_TYPE PLUMBING
J 0
(1900 4225);
DISPLAY 0.872340 (1900 4225);
PAINT GREEN (1900 4225);
DISPLAY INVISIBLE (1900 4225);
FORCEPROP 1 LAST HDL_TAP TRUE
J 0
(2225 4050);
DISPLAY 0.872340 (2225 4050);
DISPLAY INVISIBLE (2225 4050);
FORCEPROP 1 LAST PATH I157
J 0
(1898 4175);
DISPLAY 0.872340 (1898 4175);
PAINT GREEN (1898 4175);
DISPLAY INVISIBLE (1898 4175);
FORCEADD TAP..1
(2075 3425);
FORCEPROP 3 LASTPIN (2025 3425) SIG_NAME M_E_CPU1_SA_DQS_DN<0>
J 0
(2035 3435);
DISPLAY 0.659574 (2035 3435);
PAINT MONO (2035 3435);
DISPLAY INVISIBLE (2035 3435);
FORCEPROP 1 LASTPIN (2025 3425) BN 0
J 0
(2013 3433);
DISPLAY 0.680851 (2013 3433);
PAINT GREEN (2013 3433);
FORCEPROP 2 LAST CDS_LIB standard
J 0
(2075 3425);
PAINT MONO (2075 3425);
DISPLAY INVISIBLE (2075 3425);
FORCEPROP 1 LAST BODY_TYPE PLUMBING
J 0
(2075 3475);
DISPLAY 0.872340 (2075 3475);
PAINT GREEN (2075 3475);
DISPLAY INVISIBLE (2075 3475);
FORCEPROP 1 LAST HDL_TAP TRUE
J 0
(2400 3300);
DISPLAY 0.872340 (2400 3300);
DISPLAY INVISIBLE (2400 3300);
FORCEPROP 1 LAST PATH I158
J 0
(2073 3425);
DISPLAY 0.872340 (2073 3425);
PAINT GREEN (2073 3425);
DISPLAY INVISIBLE (2073 3425);
FORCEADD TAP..1
(2075 3525);
FORCEPROP 3 LASTPIN (2025 3525) SIG_NAME M_E_CPU1_SA_DQS_DN<1>
J 0
(2035 3535);
DISPLAY 0.659574 (2035 3535);
PAINT MONO (2035 3535);
DISPLAY INVISIBLE (2035 3535);
FORCEPROP 1 LASTPIN (2025 3525) BN 1
J 0
(2013 3533);
DISPLAY 0.680851 (2013 3533);
PAINT GREEN (2013 3533);
FORCEPROP 2 LAST CDS_LIB standard
J 0
(2075 3525);
DISPLAY INVISIBLE (2075 3525);
FORCEPROP 1 LAST BODY_TYPE PLUMBING
J 0
(2075 3575);
DISPLAY 0.872340 (2075 3575);
PAINT GREEN (2075 3575);
DISPLAY INVISIBLE (2075 3575);
FORCEPROP 1 LAST HDL_TAP TRUE
J 0
(2400 3400);
DISPLAY 0.872340 (2400 3400);
DISPLAY INVISIBLE (2400 3400);
FORCEPROP 1 LAST PATH I159
J 0
(2073 3525);
DISPLAY 0.872340 (2073 3525);
PAINT GREEN (2073 3525);
DISPLAY INVISIBLE (2073 3525);
FORCEADD OFFPAGE..1
(-3425 3225);
FORCEPROP 2 LAST $XR0 55 
J 0
(-3646 3225);
DISPLAY 0.638298 (-3646 3225);
PAINT MONO (-3646 3225);
FORCEPROP 2 LAST CDS_LIB standard
J 0
(-3425 3225);
PAINT MONO (-3425 3225);
DISPLAY INVISIBLE (-3425 3225);
FORCEPROP 1 LAST OFFPAGE TRUE
J 0
(-3100 3100);
DISPLAY 0.872340 (-3100 3100);
DISPLAY INVISIBLE (-3100 3100);
FORCEPROP 1 LAST COMMENT_BODY TRUE
J 0
(-3300 3125);
DISPLAY 0.872340 (-3300 3125);
PAINT GREEN (-3300 3125);
DISPLAY INVISIBLE (-3300 3125);
FORCEPROP 2 LAST PATH I16
J 0
(-3375 3300);
DISPLAY 1.021277 (-3375 3300);
DISPLAY INVISIBLE (-3375 3300);
FORCEADD TAP..1
(2075 3625);
FORCEPROP 3 LASTPIN (2025 3625) SIG_NAME M_E_CPU1_SA_DQS_DN<2>
J 0
(2035 3635);
DISPLAY 0.659574 (2035 3635);
PAINT MONO (2035 3635);
DISPLAY INVISIBLE (2035 3635);
FORCEPROP 1 LASTPIN (2025 3625) BN 2
J 0
(2013 3633);
DISPLAY 0.680851 (2013 3633);
PAINT GREEN (2013 3633);
FORCEPROP 2 LAST CDS_LIB standard
J 0
(2075 3625);
DISPLAY INVISIBLE (2075 3625);
FORCEPROP 1 LAST BODY_TYPE PLUMBING
J 0
(2075 3675);
DISPLAY 0.872340 (2075 3675);
PAINT GREEN (2075 3675);
DISPLAY INVISIBLE (2075 3675);
FORCEPROP 1 LAST HDL_TAP TRUE
J 0
(2400 3500);
DISPLAY 0.872340 (2400 3500);
DISPLAY INVISIBLE (2400 3500);
FORCEPROP 1 LAST PATH I160
J 0
(2073 3625);
DISPLAY 0.872340 (2073 3625);
PAINT GREEN (2073 3625);
DISPLAY INVISIBLE (2073 3625);
FORCEADD TAP..1
(2075 3825);
FORCEPROP 3 LASTPIN (2025 3825) SIG_NAME M_E_CPU1_SA_DQS_DN<4>
J 0
(2035 3835);
DISPLAY 0.659574 (2035 3835);
PAINT MONO (2035 3835);
DISPLAY INVISIBLE (2035 3835);
FORCEPROP 1 LASTPIN (2025 3825) BN 4
J 0
(2013 3833);
DISPLAY 0.680851 (2013 3833);
PAINT GREEN (2013 3833);
FORCEPROP 2 LAST CDS_LIB standard
J 0
(2075 3825);
PAINT MONO (2075 3825);
DISPLAY INVISIBLE (2075 3825);
FORCEPROP 1 LAST BODY_TYPE PLUMBING
J 0
(2075 3875);
DISPLAY 0.872340 (2075 3875);
PAINT GREEN (2075 3875);
DISPLAY INVISIBLE (2075 3875);
FORCEPROP 1 LAST HDL_TAP TRUE
J 0
(2400 3700);
DISPLAY 0.872340 (2400 3700);
DISPLAY INVISIBLE (2400 3700);
FORCEPROP 1 LAST PATH I161
J 0
(2073 3825);
DISPLAY 0.872340 (2073 3825);
PAINT GREEN (2073 3825);
DISPLAY INVISIBLE (2073 3825);
FORCEADD TAP..1
(2075 3725);
FORCEPROP 3 LASTPIN (2025 3725) SIG_NAME M_E_CPU1_SA_DQS_DN<3>
J 0
(2035 3735);
DISPLAY 0.659574 (2035 3735);
PAINT MONO (2035 3735);
DISPLAY INVISIBLE (2035 3735);
FORCEPROP 1 LASTPIN (2025 3725) BN 3
J 0
(2013 3733);
DISPLAY 0.680851 (2013 3733);
PAINT GREEN (2013 3733);
FORCEPROP 2 LAST CDS_LIB standard
J 0
(2075 3725);
PAINT MONO (2075 3725);
DISPLAY INVISIBLE (2075 3725);
FORCEPROP 1 LAST BODY_TYPE PLUMBING
J 0
(2075 3775);
DISPLAY 0.872340 (2075 3775);
PAINT GREEN (2075 3775);
DISPLAY INVISIBLE (2075 3775);
FORCEPROP 1 LAST HDL_TAP TRUE
J 0
(2400 3600);
DISPLAY 0.872340 (2400 3600);
DISPLAY INVISIBLE (2400 3600);
FORCEPROP 1 LAST PATH I162
J 0
(2073 3725);
DISPLAY 0.872340 (2073 3725);
PAINT GREEN (2073 3725);
DISPLAY INVISIBLE (2073 3725);
FORCEADD TAP..1
(2075 3925);
FORCEPROP 3 LASTPIN (2025 3925) SIG_NAME M_E_CPU1_SA_DQS_DN<5>
J 0
(2035 3935);
DISPLAY 0.659574 (2035 3935);
PAINT MONO (2035 3935);
DISPLAY INVISIBLE (2035 3935);
FORCEPROP 1 LASTPIN (2025 3925) BN 5
J 0
(2013 3933);
DISPLAY 0.680851 (2013 3933);
PAINT GREEN (2013 3933);
FORCEPROP 2 LAST CDS_LIB standard
J 0
(2075 3925);
DISPLAY INVISIBLE (2075 3925);
FORCEPROP 1 LAST BODY_TYPE PLUMBING
J 0
(2075 3975);
DISPLAY 0.872340 (2075 3975);
PAINT GREEN (2075 3975);
DISPLAY INVISIBLE (2075 3975);
FORCEPROP 1 LAST HDL_TAP TRUE
J 0
(2400 3800);
DISPLAY 0.872340 (2400 3800);
DISPLAY INVISIBLE (2400 3800);
FORCEPROP 1 LAST PATH I163
J 0
(2073 3925);
DISPLAY 0.872340 (2073 3925);
PAINT GREEN (2073 3925);
DISPLAY INVISIBLE (2073 3925);
FORCEADD TAP..1
(2075 4025);
FORCEPROP 3 LASTPIN (2025 4025) SIG_NAME M_E_CPU1_SA_DQS_DN<6>
J 0
(2035 4035);
DISPLAY 0.659574 (2035 4035);
PAINT MONO (2035 4035);
DISPLAY INVISIBLE (2035 4035);
FORCEPROP 1 LASTPIN (2025 4025) BN 6
J 0
(2013 4033);
DISPLAY 0.680851 (2013 4033);
PAINT GREEN (2013 4033);
FORCEPROP 2 LAST CDS_LIB standard
J 0
(2075 4025);
DISPLAY INVISIBLE (2075 4025);
FORCEPROP 1 LAST BODY_TYPE PLUMBING
J 0
(2075 4075);
DISPLAY 0.872340 (2075 4075);
PAINT GREEN (2075 4075);
DISPLAY INVISIBLE (2075 4075);
FORCEPROP 1 LAST HDL_TAP TRUE
J 0
(2400 3900);
DISPLAY 0.872340 (2400 3900);
DISPLAY INVISIBLE (2400 3900);
FORCEPROP 1 LAST PATH I164
J 0
(2073 4025);
DISPLAY 0.872340 (2073 4025);
PAINT GREEN (2073 4025);
DISPLAY INVISIBLE (2073 4025);
FORCEADD TAP..1
(2075 4125);
FORCEPROP 3 LASTPIN (2025 4125) SIG_NAME M_E_CPU1_SA_DQS_DN<7>
J 0
(2035 4135);
DISPLAY 0.659574 (2035 4135);
PAINT MONO (2035 4135);
DISPLAY INVISIBLE (2035 4135);
FORCEPROP 1 LASTPIN (2025 4125) BN 7
J 0
(2013 4133);
DISPLAY 0.680851 (2013 4133);
PAINT GREEN (2013 4133);
FORCEPROP 2 LAST CDS_LIB standard
J 0
(2075 4125);
DISPLAY INVISIBLE (2075 4125);
FORCEPROP 1 LAST BODY_TYPE PLUMBING
J 0
(2075 4175);
DISPLAY 0.872340 (2075 4175);
PAINT GREEN (2075 4175);
DISPLAY INVISIBLE (2075 4175);
FORCEPROP 1 LAST HDL_TAP TRUE
J 0
(2400 4000);
DISPLAY 0.872340 (2400 4000);
DISPLAY INVISIBLE (2400 4000);
FORCEPROP 1 LAST PATH I165
J 0
(2073 4125);
DISPLAY 0.872340 (2073 4125);
PAINT GREEN (2073 4125);
DISPLAY INVISIBLE (2073 4125);
FORCEADD TAP..1
(2075 4225);
FORCEPROP 3 LASTPIN (2025 4225) SIG_NAME M_E_CPU1_SA_DQS_DN<8>
J 0
(2035 4235);
DISPLAY 0.659574 (2035 4235);
PAINT MONO (2035 4235);
DISPLAY INVISIBLE (2035 4235);
FORCEPROP 1 LASTPIN (2025 4225) BN 8
J 0
(2013 4233);
DISPLAY 0.680851 (2013 4233);
PAINT GREEN (2013 4233);
FORCEPROP 2 LAST CDS_LIB standard
J 0
(2075 4225);
DISPLAY INVISIBLE (2075 4225);
FORCEPROP 1 LAST BODY_TYPE PLUMBING
J 0
(2075 4275);
DISPLAY 0.872340 (2075 4275);
PAINT GREEN (2075 4275);
DISPLAY INVISIBLE (2075 4275);
FORCEPROP 1 LAST HDL_TAP TRUE
J 0
(2400 4100);
DISPLAY 0.872340 (2400 4100);
DISPLAY INVISIBLE (2400 4100);
FORCEPROP 1 LAST PATH I166
J 0
(2073 4225);
DISPLAY 0.872340 (2073 4225);
PAINT GREEN (2073 4225);
DISPLAY INVISIBLE (2073 4225);
FORCEADD TAP..1
(2075 4325);
FORCEPROP 3 LASTPIN (2025 4325) SIG_NAME M_E_CPU1_SA_DQS_DN<9>
J 0
(2035 4335);
DISPLAY 0.659574 (2035 4335);
PAINT MONO (2035 4335);
DISPLAY INVISIBLE (2035 4335);
FORCEPROP 1 LASTPIN (2025 4325) BN 9
J 0
(2013 4333);
DISPLAY 0.680851 (2013 4333);
PAINT GREEN (2013 4333);
FORCEPROP 2 LAST CDS_LIB standard
J 0
(2075 4325);
DISPLAY INVISIBLE (2075 4325);
FORCEPROP 1 LAST BODY_TYPE PLUMBING
J 0
(2075 4375);
DISPLAY 0.872340 (2075 4375);
PAINT GREEN (2075 4375);
DISPLAY INVISIBLE (2075 4375);
FORCEPROP 1 LAST HDL_TAP TRUE
J 0
(2400 4200);
DISPLAY 0.872340 (2400 4200);
DISPLAY INVISIBLE (2400 4200);
FORCEPROP 1 LAST PATH I167
J 0
(2073 4325);
DISPLAY 0.872340 (2073 4325);
PAINT GREEN (2073 4325);
DISPLAY INVISIBLE (2073 4325);
FORCEADD OFFPAGE..2
(3025 3300);
FORCEPROP 2 LAST $XR1 106 
J 0
(3304 3300);
DISPLAY 0.638298 (3304 3300);
PAINT MONO (3304 3300);
FORCEPROP 2 LAST $XR0 55 
J 0
(3214 3300);
DISPLAY 0.638298 (3214 3300);
PAINT MONO (3214 3300);
FORCEPROP 2 LAST CDS_LIB standard
J 0
(3025 3300);
PAINT MONO (3025 3300);
DISPLAY INVISIBLE (3025 3300);
FORCEPROP 1 LAST OFFPAGE TRUE
J 0
(3350 3175);
DISPLAY 1.170213 (3350 3175);
PAINT GREEN (3350 3175);
DISPLAY INVISIBLE (3350 3175);
FORCEPROP 1 LAST COMMENT_BODY TRUE
J 0
(2980 3205);
DISPLAY 1.170213 (2980 3205);
PAINT GREEN (2980 3205);
DISPLAY INVISIBLE (2980 3205);
FORCEPROP 2 LAST PATH I168
J 0
(3200 3375);
DISPLAY 1.021277 (3200 3375);
DISPLAY INVISIBLE (3200 3375);
FORCEADD OFFPAGE..2
(3025 3350);
FORCEPROP 2 LAST $XR1 106 
J 0
(3304 3350);
DISPLAY 0.638298 (3304 3350);
PAINT MONO (3304 3350);
FORCEPROP 2 LAST $XR0 55 
J 0
(3214 3350);
DISPLAY 0.638298 (3214 3350);
PAINT MONO (3214 3350);
FORCEPROP 2 LAST CDS_LIB standard
J 0
(3025 3350);
PAINT MONO (3025 3350);
DISPLAY INVISIBLE (3025 3350);
FORCEPROP 1 LAST OFFPAGE TRUE
J 0
(3350 3225);
DISPLAY 1.170213 (3350 3225);
PAINT GREEN (3350 3225);
DISPLAY INVISIBLE (3350 3225);
FORCEPROP 1 LAST COMMENT_BODY TRUE
J 0
(2980 3255);
DISPLAY 1.170213 (2980 3255);
PAINT GREEN (2980 3255);
DISPLAY INVISIBLE (2980 3255);
FORCEPROP 2 LAST PATH I169
J 0
(3200 3425);
DISPLAY 1.021277 (3200 3425);
DISPLAY INVISIBLE (3200 3425);
FORCEADD OFFPAGE..1
(-3425 3275);
FORCEPROP 2 LAST $XR0 55 
J 0
(-3646 3275);
DISPLAY 0.638298 (-3646 3275);
PAINT MONO (-3646 3275);
FORCEPROP 2 LAST CDS_LIB standard
J 0
(-3425 3275);
PAINT MONO (-3425 3275);
DISPLAY INVISIBLE (-3425 3275);
FORCEPROP 1 LAST OFFPAGE TRUE
J 0
(-3100 3150);
DISPLAY 0.872340 (-3100 3150);
DISPLAY INVISIBLE (-3100 3150);
FORCEPROP 1 LAST COMMENT_BODY TRUE
J 0
(-3300 3175);
DISPLAY 0.872340 (-3300 3175);
PAINT GREEN (-3300 3175);
DISPLAY INVISIBLE (-3300 3175);
FORCEPROP 2 LAST PATH I17
J 0
(-3375 3350);
DISPLAY 1.021277 (-3375 3350);
DISPLAY INVISIBLE (-3375 3350);
FORCEADD OFFPAGE..2
(3025 4350);
FORCEPROP 2 LAST $XR1 106 
J 0
(3304 4350);
DISPLAY 0.638298 (3304 4350);
PAINT MONO (3304 4350);
FORCEPROP 2 LAST $XR0 55 
J 0
(3214 4350);
DISPLAY 0.638298 (3214 4350);
PAINT MONO (3214 4350);
FORCEPROP 2 LAST CDS_LIB standard
J 0
(3025 4350);
PAINT MONO (3025 4350);
DISPLAY INVISIBLE (3025 4350);
FORCEPROP 1 LAST OFFPAGE TRUE
J 0
(3350 4225);
DISPLAY 1.170213 (3350 4225);
PAINT GREEN (3350 4225);
DISPLAY INVISIBLE (3350 4225);
FORCEPROP 1 LAST COMMENT_BODY TRUE
J 0
(2980 4255);
DISPLAY 1.170213 (2980 4255);
PAINT GREEN (2980 4255);
DISPLAY INVISIBLE (2980 4255);
FORCEPROP 2 LAST PATH I170
J 0
(3200 4425);
DISPLAY 1.021277 (3200 4425);
DISPLAY INVISIBLE (3200 4425);
FORCEADD OFFPAGE..3
(-25 4400);
FORCEPROP 2 LAST $XR1 106 
J 0
(279 4400);
DISPLAY 0.638298 (279 4400);
PAINT MONO (279 4400);
FORCEPROP 2 LAST $XR0 55 
J 0
(189 4400);
DISPLAY 0.638298 (189 4400);
PAINT MONO (189 4400);
FORCEPROP 2 LAST CDS_LIB standard
J 2
(-25 4400);
DISPLAY INVISIBLE (-25 4400);
FORCEPROP 1 LAST OFFPAGE TRUE
J 0
(300 4275);
DISPLAY 0.872340 (300 4275);
DISPLAY INVISIBLE (300 4275);
FORCEPROP 1 LAST COMMENT_BODY TRUE
J 0
(-75 4300);
DISPLAY 0.872340 (-75 4300);
PAINT GREEN (-75 4300);
DISPLAY INVISIBLE (-75 4300);
FORCEPROP 2 LAST PATH I171
J 0
(175 4475);
DISPLAY 1.021277 (175 4475);
DISPLAY INVISIBLE (175 4475);
FORCEADD TAP..1
(1900 4375);
FORCEPROP 3 LASTPIN (1850 4375) SIG_NAME M_E_CPU1_SA_DQS_DP<9>
J 0
(1860 4385);
DISPLAY 0.659574 (1860 4385);
PAINT MONO (1860 4385);
DISPLAY INVISIBLE (1860 4385);
FORCEPROP 1 LASTPIN (1850 4375) BN 9
J 0
(1838 4383);
DISPLAY 0.680851 (1838 4383);
PAINT GREEN (1838 4383);
FORCEPROP 2 LAST CDS_LIB standard
J 0
(1900 4375);
DISPLAY INVISIBLE (1900 4375);
FORCEPROP 1 LAST BODY_TYPE PLUMBING
J 0
(1900 4425);
DISPLAY 0.872340 (1900 4425);
PAINT GREEN (1900 4425);
DISPLAY INVISIBLE (1900 4425);
FORCEPROP 1 LAST HDL_TAP TRUE
J 0
(2225 4250);
DISPLAY 0.872340 (2225 4250);
DISPLAY INVISIBLE (2225 4250);
FORCEPROP 1 LAST PATH I172
J 0
(1898 4375);
DISPLAY 0.872340 (1898 4375);
PAINT GREEN (1898 4375);
DISPLAY INVISIBLE (1898 4375);
FORCEADD OFFPAGE..2
(3025 4400);
FORCEPROP 2 LAST $XR1 106 
J 0
(3304 4400);
DISPLAY 0.638298 (3304 4400);
PAINT MONO (3304 4400);
FORCEPROP 2 LAST $XR0 55 
J 0
(3214 4400);
DISPLAY 0.638298 (3214 4400);
PAINT MONO (3214 4400);
FORCEPROP 2 LAST CDS_LIB standard
J 0
(3025 4400);
PAINT MONO (3025 4400);
DISPLAY INVISIBLE (3025 4400);
FORCEPROP 1 LAST OFFPAGE TRUE
J 0
(3350 4275);
DISPLAY 1.170213 (3350 4275);
PAINT GREEN (3350 4275);
DISPLAY INVISIBLE (3350 4275);
FORCEPROP 1 LAST COMMENT_BODY TRUE
J 0
(2980 4305);
DISPLAY 1.170213 (2980 4305);
PAINT GREEN (2980 4305);
DISPLAY INVISIBLE (2980 4305);
FORCEPROP 2 LAST PATH I173
J 0
(3200 4475);
DISPLAY 1.021277 (3200 4475);
DISPLAY INVISIBLE (3200 4475);
FORCEADD UNIVERSAL_GND..1
(3575 675);
FORCEPROP 3 LASTPIN (3575 725) SIG_NAME GND\g
J 0
(3585 735);
DISPLAY 0.659574 (3585 735);
PAINT MONO (3585 735);
DISPLAY INVISIBLE (3585 735);
FORCEPROP 1 LAST PATH I174
J 0
(3650 675);
DISPLAY 0.872340 (3650 675);
PAINT AQUA (3650 675);
DISPLAY INVISIBLE (3650 675);
FORCEPROP 1 LAST HDL_POWER GND
J 1
(3600 600);
DISPLAY 0.872340 (3600 600);
PAINT GREEN (3600 600);
DISPLAY INVISIBLE (3600 600);
FORCEPROP 2 LAST CDS_LIB logical_power
J 0
(3575 675);
PAINT MONO (3575 675);
DISPLAY INVISIBLE (3575 675);
FORCEADD UNIVERSAL_GND..1
(5275 675);
FORCEPROP 3 LASTPIN (5275 725) SIG_NAME GND\g
J 0
(5285 735);
DISPLAY 0.659574 (5285 735);
PAINT MONO (5285 735);
DISPLAY INVISIBLE (5285 735);
FORCEPROP 1 LAST PATH I176
J 0
(5350 675);
DISPLAY 0.872340 (5350 675);
PAINT AQUA (5350 675);
DISPLAY INVISIBLE (5350 675);
FORCEPROP 1 LAST HDL_POWER GND
J 1
(5300 600);
DISPLAY 0.872340 (5300 600);
PAINT GREEN (5300 600);
DISPLAY INVISIBLE (5300 600);
FORCEPROP 2 LAST CDS_LIB logical_power
J 0
(5275 675);
PAINT MONO (5275 675);
DISPLAY INVISIBLE (5275 675);
FORCEADD VCC_CORE..1
(3575 4925);
FORCEPROP 3 LASTPIN (3575 4875) SIG_NAME P12V_S3_AUX_CPU1_NVDIMM\g
J 0
(3585 4885);
DISPLAY 0.659574 (3585 4885);
PAINT MONO (3585 4885);
DISPLAY INVISIBLE (3585 4885);
FORCEPROP 1 LAST HDL_POWER P12V_S3_AUX_CPU1_NVDIMM
J 1
(3575 4975);
DISPLAY 1.148936 (3575 4975);
PAINT GREEN (3575 4975);
FORCEPROP 2 LAST CDS_LIB logical_power
J 0
(3575 4925);
PAINT MONO (3575 4925);
DISPLAY INVISIBLE (3575 4925);
FORCEPROP 1 LAST PATH I177
J 0
(3625 4950);
DISPLAY 0.872340 (3625 4950);
PAINT AQUA (3625 4950);
DISPLAY INVISIBLE (3625 4950);
FORCEADD SCONN288_ADR50017P087CC..3
(4425 2750);
FORCEPROP 1 LAST PART_NUMBER DFHST8FS460
J 0
(3970 4674);
DISPLAY 0.723404 (3970 4674);
PAINT GREEN (3970 4674);
DISPLAY INVISIBLE (3970 4674);
FORCEPROP 1 LAST MATERIAL IO
J 0
(3970 4547);
DISPLAY 0.723404 (3970 4547);
PAINT GREEN (3970 4547);
FORCEPROP 2 LAST PART_TYPE SMLF
J 0
(3975 4825);
DISPLAY 1.021277 (3975 4825);
FORCEPROP 2 LAST VALUE SCONN288_ADR50017-P087CC
J 0
(3975 4775);
DISPLAY 1.021277 (3975 4775);
FORCEPROP 1 LAST $LOCATION J26
J 0
(3975 4725);
DISPLAY 0.723404 (3975 4725);
PAINT GREEN (3975 4725);
FORCEPROP 0 LASTPIN (5025 1125) $PN G1
J 0
(5035 1135);
DISPLAY 0.680851 (5035 1135);
PAINT MONO (5035 1135);
FORCEPROP 0 LASTPIN (5025 1075) $PN G2
J 0
(5035 1085);
DISPLAY 0.680851 (5035 1085);
PAINT MONO (5035 1085);
FORCEPROP 0 LASTPIN (5025 1025) $PN G3
J 0
(5035 1035);
DISPLAY 0.680851 (5035 1035);
PAINT MONO (5035 1035);
FORCEPROP 0 LASTPIN (3825 4275) $PN 1
J 2
(3815 4285);
DISPLAY 0.680851 (3815 4285);
PAINT MONO (3815 4285);
FORCEPROP 0 LASTPIN (3825 4325) $PN 145
J 2
(3815 4335);
DISPLAY 0.680851 (3815 4335);
PAINT MONO (3815 4335);
FORCEPROP 0 LASTPIN (3825 4375) $PN 146
J 2
(3815 4385);
DISPLAY 0.680851 (3815 4385);
PAINT MONO (3815 4385);
FORCEPROP 0 LASTPIN (5025 1225) $PN 6
J 0
(5035 1235);
DISPLAY 0.680851 (5035 1235);
PAINT MONO (5035 1235);
FORCEPROP 0 LASTPIN (5025 1275) $PN 8
J 0
(5035 1285);
DISPLAY 0.680851 (5035 1285);
PAINT MONO (5035 1285);
FORCEPROP 0 LASTPIN (5025 1325) $PN 10
J 0
(5035 1335);
DISPLAY 0.680851 (5035 1335);
PAINT MONO (5035 1335);
FORCEPROP 0 LASTPIN (5025 1375) $PN 13
J 0
(5035 1385);
DISPLAY 0.680851 (5035 1385);
PAINT MONO (5035 1385);
FORCEPROP 0 LASTPIN (5025 1425) $PN 15
J 0
(5035 1435);
DISPLAY 0.680851 (5035 1435);
PAINT MONO (5035 1435);
FORCEPROP 0 LASTPIN (5025 1475) $PN 17
J 0
(5035 1485);
DISPLAY 0.680851 (5035 1485);
PAINT MONO (5035 1485);
FORCEPROP 0 LASTPIN (5025 1525) $PN 19
J 0
(5035 1535);
DISPLAY 0.680851 (5035 1535);
PAINT MONO (5035 1535);
FORCEPROP 0 LASTPIN (5025 1575) $PN 21
J 0
(5035 1585);
DISPLAY 0.680851 (5035 1585);
PAINT MONO (5035 1585);
FORCEPROP 0 LASTPIN (5025 1625) $PN 24
J 0
(5035 1635);
DISPLAY 0.680851 (5035 1635);
PAINT MONO (5035 1635);
FORCEPROP 0 LASTPIN (5025 1675) $PN 26
J 0
(5035 1685);
DISPLAY 0.680851 (5035 1685);
PAINT MONO (5035 1685);
FORCEPROP 0 LASTPIN (5025 1725) $PN 28
J 0
(5035 1735);
DISPLAY 0.680851 (5035 1735);
PAINT MONO (5035 1735);
FORCEPROP 0 LASTPIN (5025 1775) $PN 30
J 0
(5035 1785);
DISPLAY 0.680851 (5035 1785);
PAINT MONO (5035 1785);
FORCEPROP 0 LASTPIN (5025 1825) $PN 32
J 0
(5035 1835);
DISPLAY 0.680851 (5035 1835);
PAINT MONO (5035 1835);
FORCEPROP 0 LASTPIN (5025 1875) $PN 35
J 0
(5035 1885);
DISPLAY 0.680851 (5035 1885);
PAINT MONO (5035 1885);
FORCEPROP 0 LASTPIN (5025 1925) $PN 37
J 0
(5035 1935);
DISPLAY 0.680851 (5035 1935);
PAINT MONO (5035 1935);
FORCEPROP 0 LASTPIN (5025 1975) $PN 39
J 0
(5035 1985);
DISPLAY 0.680851 (5035 1985);
PAINT MONO (5035 1985);
FORCEPROP 0 LASTPIN (5025 2025) $PN 41
J 0
(5035 2035);
DISPLAY 0.680851 (5035 2035);
PAINT MONO (5035 2035);
FORCEPROP 0 LASTPIN (5025 2075) $PN 43
J 0
(5035 2085);
DISPLAY 0.680851 (5035 2085);
PAINT MONO (5035 2085);
FORCEPROP 0 LASTPIN (5025 2125) $PN 46
J 0
(5035 2135);
DISPLAY 0.680851 (5035 2135);
PAINT MONO (5035 2135);
FORCEPROP 0 LASTPIN (5025 2175) $PN 48
J 0
(5035 2185);
DISPLAY 0.680851 (5035 2185);
PAINT MONO (5035 2185);
FORCEPROP 0 LASTPIN (5025 2225) $PN 50
J 0
(5035 2235);
DISPLAY 0.680851 (5035 2235);
PAINT MONO (5035 2235);
FORCEPROP 0 LASTPIN (5025 2275) $PN 52
J 0
(5035 2285);
DISPLAY 0.680851 (5035 2285);
PAINT MONO (5035 2285);
FORCEPROP 0 LASTPIN (5025 2325) $PN 54
J 0
(5035 2335);
DISPLAY 0.680851 (5035 2335);
PAINT MONO (5035 2335);
FORCEPROP 0 LASTPIN (5025 2375) $PN 57
J 0
(5035 2385);
DISPLAY 0.680851 (5035 2385);
PAINT MONO (5035 2385);
FORCEPROP 0 LASTPIN (5025 2425) $PN 59
J 0
(5035 2435);
DISPLAY 0.680851 (5035 2435);
PAINT MONO (5035 2435);
FORCEPROP 0 LASTPIN (5025 2475) $PN 61
J 0
(5035 2485);
DISPLAY 0.680851 (5035 2485);
PAINT MONO (5035 2485);
FORCEPROP 0 LASTPIN (5025 2525) $PN 63
J 0
(5035 2535);
DISPLAY 0.680851 (5035 2535);
PAINT MONO (5035 2535);
FORCEPROP 0 LASTPIN (5025 2575) $PN 65
J 0
(5035 2585);
DISPLAY 0.680851 (5035 2585);
PAINT MONO (5035 2585);
FORCEPROP 0 LASTPIN (5025 2625) $PN 67
J 0
(5035 2635);
DISPLAY 0.680851 (5035 2635);
PAINT MONO (5035 2635);
FORCEPROP 0 LASTPIN (5025 2675) $PN 69
J 0
(5035 2685);
DISPLAY 0.680851 (5035 2685);
PAINT MONO (5035 2685);
FORCEPROP 0 LASTPIN (5025 2725) $PN 71
J 0
(5035 2735);
DISPLAY 0.680851 (5035 2735);
PAINT MONO (5035 2735);
FORCEPROP 0 LASTPIN (5025 2775) $PN 73
J 0
(5035 2785);
DISPLAY 0.680851 (5035 2785);
PAINT MONO (5035 2785);
FORCEPROP 0 LASTPIN (5025 2825) $PN 75
J 0
(5035 2835);
DISPLAY 0.680851 (5035 2835);
PAINT MONO (5035 2835);
FORCEPROP 0 LASTPIN (5025 2875) $PN 77
J 0
(5035 2885);
DISPLAY 0.680851 (5035 2885);
PAINT MONO (5035 2885);
FORCEPROP 0 LASTPIN (5025 2925) $PN 79
J 0
(5035 2935);
DISPLAY 0.680851 (5035 2935);
PAINT MONO (5035 2935);
FORCEPROP 0 LASTPIN (5025 2975) $PN 81
J 0
(5035 2985);
DISPLAY 0.680851 (5035 2985);
PAINT MONO (5035 2985);
FORCEPROP 0 LASTPIN (5025 3025) $PN 83
J 0
(5035 3035);
DISPLAY 0.680851 (5035 3035);
PAINT MONO (5035 3035);
FORCEPROP 0 LASTPIN (5025 3075) $PN 85
J 0
(5035 3085);
DISPLAY 0.680851 (5035 3085);
PAINT MONO (5035 3085);
FORCEPROP 0 LASTPIN (5025 3125) $PN 88
J 0
(5035 3135);
DISPLAY 0.680851 (5035 3135);
PAINT MONO (5035 3135);
FORCEPROP 0 LASTPIN (5025 3175) $PN 90
J 0
(5035 3185);
DISPLAY 0.680851 (5035 3185);
PAINT MONO (5035 3185);
FORCEPROP 0 LASTPIN (5025 3225) $PN 92
J 0
(5035 3235);
DISPLAY 0.680851 (5035 3235);
PAINT MONO (5035 3235);
FORCEPROP 0 LASTPIN (5025 3275) $PN 95
J 0
(5035 3285);
DISPLAY 0.680851 (5035 3285);
PAINT MONO (5035 3285);
FORCEPROP 0 LASTPIN (5025 3325) $PN 97
J 0
(5035 3335);
DISPLAY 0.680851 (5035 3335);
PAINT MONO (5035 3335);
FORCEPROP 0 LASTPIN (5025 3375) $PN 99
J 0
(5035 3385);
DISPLAY 0.680851 (5035 3385);
PAINT MONO (5035 3385);
FORCEPROP 0 LASTPIN (5025 3425) $PN 101
J 0
(5035 3435);
DISPLAY 0.680851 (5035 3435);
PAINT MONO (5035 3435);
FORCEPROP 0 LASTPIN (5025 3475) $PN 103
J 0
(5035 3485);
DISPLAY 0.680851 (5035 3485);
PAINT MONO (5035 3485);
FORCEPROP 0 LASTPIN (5025 3525) $PN 106
J 0
(5035 3535);
DISPLAY 0.680851 (5035 3535);
PAINT MONO (5035 3535);
FORCEPROP 0 LASTPIN (5025 3575) $PN 108
J 0
(5035 3585);
DISPLAY 0.680851 (5035 3585);
PAINT MONO (5035 3585);
FORCEPROP 0 LASTPIN (5025 3625) $PN 110
J 0
(5035 3635);
DISPLAY 0.680851 (5035 3635);
PAINT MONO (5035 3635);
FORCEPROP 0 LASTPIN (5025 3675) $PN 112
J 0
(5035 3685);
DISPLAY 0.680851 (5035 3685);
PAINT MONO (5035 3685);
FORCEPROP 0 LASTPIN (5025 3725) $PN 114
J 0
(5035 3735);
DISPLAY 0.680851 (5035 3735);
PAINT MONO (5035 3735);
FORCEPROP 0 LASTPIN (5025 3775) $PN 117
J 0
(5035 3785);
DISPLAY 0.680851 (5035 3785);
PAINT MONO (5035 3785);
FORCEPROP 0 LASTPIN (5025 3825) $PN 119
J 0
(5035 3835);
DISPLAY 0.680851 (5035 3835);
PAINT MONO (5035 3835);
FORCEPROP 0 LASTPIN (5025 3875) $PN 121
J 0
(5035 3885);
DISPLAY 0.680851 (5035 3885);
PAINT MONO (5035 3885);
FORCEPROP 0 LASTPIN (5025 3925) $PN 123
J 0
(5035 3935);
DISPLAY 0.680851 (5035 3935);
PAINT MONO (5035 3935);
FORCEPROP 0 LASTPIN (5025 3975) $PN 125
J 0
(5035 3985);
DISPLAY 0.680851 (5035 3985);
PAINT MONO (5035 3985);
FORCEPROP 0 LASTPIN (5025 4025) $PN 128
J 0
(5035 4035);
DISPLAY 0.680851 (5035 4035);
PAINT MONO (5035 4035);
FORCEPROP 0 LASTPIN (5025 4075) $PN 130
J 0
(5035 4085);
DISPLAY 0.680851 (5035 4085);
PAINT MONO (5035 4085);
FORCEPROP 0 LASTPIN (5025 4125) $PN 132
J 0
(5035 4135);
DISPLAY 0.680851 (5035 4135);
PAINT MONO (5035 4135);
FORCEPROP 0 LASTPIN (5025 4175) $PN 134
J 0
(5035 4185);
DISPLAY 0.680851 (5035 4185);
PAINT MONO (5035 4185);
FORCEPROP 0 LASTPIN (5025 4225) $PN 136
J 0
(5035 4235);
DISPLAY 0.680851 (5035 4235);
PAINT MONO (5035 4235);
FORCEPROP 0 LASTPIN (5025 4275) $PN 139
J 0
(5035 4285);
DISPLAY 0.680851 (5035 4285);
PAINT MONO (5035 4285);
FORCEPROP 0 LASTPIN (5025 4325) $PN 141
J 0
(5035 4335);
DISPLAY 0.680851 (5035 4335);
PAINT MONO (5035 4335);
FORCEPROP 0 LASTPIN (5025 4375) $PN 143
J 0
(5035 4385);
DISPLAY 0.680851 (5035 4385);
PAINT MONO (5035 4385);
FORCEPROP 0 LASTPIN (3825 1125) $PN 151
J 2
(3815 1135);
DISPLAY 0.680851 (3815 1135);
PAINT MONO (3815 1135);
FORCEPROP 0 LASTPIN (3825 1175) $PN 153
J 2
(3815 1185);
DISPLAY 0.680851 (3815 1185);
PAINT MONO (3815 1185);
FORCEPROP 0 LASTPIN (3825 1225) $PN 155
J 2
(3815 1235);
DISPLAY 0.680851 (3815 1235);
PAINT MONO (3815 1235);
FORCEPROP 0 LASTPIN (3825 1275) $PN 158
J 2
(3815 1285);
DISPLAY 0.680851 (3815 1285);
PAINT MONO (3815 1285);
FORCEPROP 0 LASTPIN (3825 1325) $PN 160
J 2
(3815 1335);
DISPLAY 0.680851 (3815 1335);
PAINT MONO (3815 1335);
FORCEPROP 0 LASTPIN (3825 1375) $PN 162
J 2
(3815 1385);
DISPLAY 0.680851 (3815 1385);
PAINT MONO (3815 1385);
FORCEPROP 0 LASTPIN (3825 1425) $PN 164
J 2
(3815 1435);
DISPLAY 0.680851 (3815 1435);
PAINT MONO (3815 1435);
FORCEPROP 0 LASTPIN (3825 1475) $PN 166
J 2
(3815 1485);
DISPLAY 0.680851 (3815 1485);
PAINT MONO (3815 1485);
FORCEPROP 0 LASTPIN (3825 1525) $PN 169
J 2
(3815 1535);
DISPLAY 0.680851 (3815 1535);
PAINT MONO (3815 1535);
FORCEPROP 0 LASTPIN (3825 1575) $PN 171
J 2
(3815 1585);
DISPLAY 0.680851 (3815 1585);
PAINT MONO (3815 1585);
FORCEPROP 0 LASTPIN (3825 1625) $PN 173
J 2
(3815 1635);
DISPLAY 0.680851 (3815 1635);
PAINT MONO (3815 1635);
FORCEPROP 0 LASTPIN (3825 1675) $PN 175
J 2
(3815 1685);
DISPLAY 0.680851 (3815 1685);
PAINT MONO (3815 1685);
FORCEPROP 0 LASTPIN (3825 1725) $PN 177
J 2
(3815 1735);
DISPLAY 0.680851 (3815 1735);
PAINT MONO (3815 1735);
FORCEPROP 0 LASTPIN (3825 1775) $PN 180
J 2
(3815 1785);
DISPLAY 0.680851 (3815 1785);
PAINT MONO (3815 1785);
FORCEPROP 0 LASTPIN (3825 1825) $PN 182
J 2
(3815 1835);
DISPLAY 0.680851 (3815 1835);
PAINT MONO (3815 1835);
FORCEPROP 0 LASTPIN (3825 1875) $PN 184
J 2
(3815 1885);
DISPLAY 0.680851 (3815 1885);
PAINT MONO (3815 1885);
FORCEPROP 0 LASTPIN (3825 1925) $PN 186
J 2
(3815 1935);
DISPLAY 0.680851 (3815 1935);
PAINT MONO (3815 1935);
FORCEPROP 0 LASTPIN (3825 1975) $PN 188
J 2
(3815 1985);
DISPLAY 0.680851 (3815 1985);
PAINT MONO (3815 1985);
FORCEPROP 0 LASTPIN (3825 2025) $PN 191
J 2
(3815 2035);
DISPLAY 0.680851 (3815 2035);
PAINT MONO (3815 2035);
FORCEPROP 0 LASTPIN (3825 2075) $PN 193
J 2
(3815 2085);
DISPLAY 0.680851 (3815 2085);
PAINT MONO (3815 2085);
FORCEPROP 0 LASTPIN (3825 2125) $PN 195
J 2
(3815 2135);
DISPLAY 0.680851 (3815 2135);
PAINT MONO (3815 2135);
FORCEPROP 0 LASTPIN (3825 2175) $PN 197
J 2
(3815 2185);
DISPLAY 0.680851 (3815 2185);
PAINT MONO (3815 2185);
FORCEPROP 0 LASTPIN (3825 2225) $PN 199
J 2
(3815 2235);
DISPLAY 0.680851 (3815 2235);
PAINT MONO (3815 2235);
FORCEPROP 0 LASTPIN (3825 2275) $PN 202
J 2
(3815 2285);
DISPLAY 0.680851 (3815 2285);
PAINT MONO (3815 2285);
FORCEPROP 0 LASTPIN (3825 2325) $PN 204
J 2
(3815 2335);
DISPLAY 0.680851 (3815 2335);
PAINT MONO (3815 2335);
FORCEPROP 0 LASTPIN (3825 2375) $PN 206
J 2
(3815 2385);
DISPLAY 0.680851 (3815 2385);
PAINT MONO (3815 2385);
FORCEPROP 0 LASTPIN (3825 2425) $PN 208
J 2
(3815 2435);
DISPLAY 0.680851 (3815 2435);
PAINT MONO (3815 2435);
FORCEPROP 0 LASTPIN (3825 2475) $PN 210
J 2
(3815 2485);
DISPLAY 0.680851 (3815 2485);
PAINT MONO (3815 2485);
FORCEPROP 0 LASTPIN (3825 2525) $PN 212
J 2
(3815 2535);
DISPLAY 0.680851 (3815 2535);
PAINT MONO (3815 2535);
FORCEPROP 0 LASTPIN (3825 2575) $PN 214
J 2
(3815 2585);
DISPLAY 0.680851 (3815 2585);
PAINT MONO (3815 2585);
FORCEPROP 0 LASTPIN (3825 2625) $PN 216
J 2
(3815 2635);
DISPLAY 0.680851 (3815 2635);
PAINT MONO (3815 2635);
FORCEPROP 0 LASTPIN (3825 2675) $PN 219
J 2
(3815 2685);
DISPLAY 0.680851 (3815 2685);
PAINT MONO (3815 2685);
FORCEPROP 0 LASTPIN (3825 2725) $PN 222
J 2
(3815 2735);
DISPLAY 0.680851 (3815 2735);
PAINT MONO (3815 2735);
FORCEPROP 0 LASTPIN (3825 2775) $PN 224
J 2
(3815 2785);
DISPLAY 0.680851 (3815 2785);
PAINT MONO (3815 2785);
FORCEPROP 0 LASTPIN (3825 2825) $PN 226
J 2
(3815 2835);
DISPLAY 0.680851 (3815 2835);
PAINT MONO (3815 2835);
FORCEPROP 0 LASTPIN (3825 2875) $PN 228
J 2
(3815 2885);
DISPLAY 0.680851 (3815 2885);
PAINT MONO (3815 2885);
FORCEPROP 0 LASTPIN (3825 2925) $PN 230
J 2
(3815 2935);
DISPLAY 0.680851 (3815 2935);
PAINT MONO (3815 2935);
FORCEPROP 0 LASTPIN (3825 2975) $PN 233
J 2
(3815 2985);
DISPLAY 0.680851 (3815 2985);
PAINT MONO (3815 2985);
FORCEPROP 0 LASTPIN (3825 3025) $PN 235
J 2
(3815 3035);
DISPLAY 0.680851 (3815 3035);
PAINT MONO (3815 3035);
FORCEPROP 0 LASTPIN (3825 3075) $PN 237
J 2
(3815 3085);
DISPLAY 0.680851 (3815 3085);
PAINT MONO (3815 3085);
FORCEPROP 0 LASTPIN (3825 3125) $PN 240
J 2
(3815 3135);
DISPLAY 0.680851 (3815 3135);
PAINT MONO (3815 3135);
FORCEPROP 0 LASTPIN (3825 3175) $PN 242
J 2
(3815 3185);
DISPLAY 0.680851 (3815 3185);
PAINT MONO (3815 3185);
FORCEPROP 0 LASTPIN (3825 3225) $PN 244
J 2
(3815 3235);
DISPLAY 0.680851 (3815 3235);
PAINT MONO (3815 3235);
FORCEPROP 0 LASTPIN (3825 3275) $PN 246
J 2
(3815 3285);
DISPLAY 0.680851 (3815 3285);
PAINT MONO (3815 3285);
FORCEPROP 0 LASTPIN (3825 3325) $PN 248
J 2
(3815 3335);
DISPLAY 0.680851 (3815 3335);
PAINT MONO (3815 3335);
FORCEPROP 0 LASTPIN (3825 3375) $PN 251
J 2
(3815 3385);
DISPLAY 0.680851 (3815 3385);
PAINT MONO (3815 3385);
FORCEPROP 0 LASTPIN (3825 3425) $PN 253
J 2
(3815 3435);
DISPLAY 0.680851 (3815 3435);
PAINT MONO (3815 3435);
FORCEPROP 0 LASTPIN (3825 3475) $PN 255
J 2
(3815 3485);
DISPLAY 0.680851 (3815 3485);
PAINT MONO (3815 3485);
FORCEPROP 0 LASTPIN (3825 3525) $PN 257
J 2
(3815 3535);
DISPLAY 0.680851 (3815 3535);
PAINT MONO (3815 3535);
FORCEPROP 0 LASTPIN (3825 3575) $PN 259
J 2
(3815 3585);
DISPLAY 0.680851 (3815 3585);
PAINT MONO (3815 3585);
FORCEPROP 0 LASTPIN (3825 3625) $PN 262
J 2
(3815 3635);
DISPLAY 0.680851 (3815 3635);
PAINT MONO (3815 3635);
FORCEPROP 0 LASTPIN (3825 3675) $PN 264
J 2
(3815 3685);
DISPLAY 0.680851 (3815 3685);
PAINT MONO (3815 3685);
FORCEPROP 0 LASTPIN (3825 3725) $PN 266
J 2
(3815 3735);
DISPLAY 0.680851 (3815 3735);
PAINT MONO (3815 3735);
FORCEPROP 0 LASTPIN (3825 3775) $PN 268
J 2
(3815 3785);
DISPLAY 0.680851 (3815 3785);
PAINT MONO (3815 3785);
FORCEPROP 0 LASTPIN (3825 3825) $PN 270
J 2
(3815 3835);
DISPLAY 0.680851 (3815 3835);
PAINT MONO (3815 3835);
FORCEPROP 0 LASTPIN (3825 3875) $PN 273
J 2
(3815 3885);
DISPLAY 0.680851 (3815 3885);
PAINT MONO (3815 3885);
FORCEPROP 0 LASTPIN (3825 3925) $PN 275
J 2
(3815 3935);
DISPLAY 0.680851 (3815 3935);
PAINT MONO (3815 3935);
FORCEPROP 0 LASTPIN (3825 3975) $PN 277
J 2
(3815 3985);
DISPLAY 0.680851 (3815 3985);
PAINT MONO (3815 3985);
FORCEPROP 0 LASTPIN (3825 4025) $PN 279
J 2
(3815 4035);
DISPLAY 0.680851 (3815 4035);
PAINT MONO (3815 4035);
FORCEPROP 0 LASTPIN (3825 4075) $PN 281
J 2
(3815 4085);
DISPLAY 0.680851 (3815 4085);
PAINT MONO (3815 4085);
FORCEPROP 0 LASTPIN (3825 4125) $PN 284
J 2
(3815 4135);
DISPLAY 0.680851 (3815 4135);
PAINT MONO (3815 4135);
FORCEPROP 0 LASTPIN (3825 4175) $PN 286
J 2
(3815 4185);
DISPLAY 0.680851 (3815 4185);
PAINT MONO (3815 4185);
FORCEPROP 0 LASTPIN (3825 4225) $PN 288
J 2
(3815 4235);
DISPLAY 0.680851 (3815 4235);
PAINT MONO (3815 4235);
FORCEPROP 1 LAST NEEDS_NO_SIZE TRUE
J 0
(4425 2750);
DISPLAY 0.723404 (4425 2750);
PAINT GREEN (4425 2750);
DISPLAY INVISIBLE (4425 2750);
FORCEPROP 1 LAST CDS_LMAN_SYM_OUTLINE -450,1775,450,-1775
J 0
(4425 2750);
DISPLAY 0.468085 (4425 2750);
PAINT GREEN (4425 2750);
DISPLAY INVISIBLE (4425 2750);
FORCEPROP 2 LAST CDS_LIB pure_quanta
J 0
(4425 2750);
DISPLAY INVISIBLE (4425 2750);
FORCEPROP 1 LAST PATH I179
J 0
(4425 2750);
DISPLAY 0.723404 (4425 2750);
PAINT GREEN (4425 2750);
DISPLAY INVISIBLE (4425 2750);
FORCEPROP 2 LAST CDS_LOCATION J26
J 0
(3975 4875);
DISPLAY 1.021277 (3975 4875);
DISPLAY INVISIBLE (3975 4875);
FORCEPROP 0 LAST $SEC 3
J 0
(3975 4875);
DISPLAY 0.680851 (3975 4875);
PAINT MONO (3975 4875);
DISPLAY INVISIBLE (3975 4875);
FORCEPROP 2 LAST CDS_SEC 3
J 0
(3975 4875);
DISPLAY 1.021277 (3975 4875);
DISPLAY INVISIBLE (3975 4875);
FORCEADD OFFPAGE..1
(-3425 3125);
FORCEPROP 2 LAST $XR0 55 
J 0
(-3646 3125);
DISPLAY 0.638298 (-3646 3125);
PAINT MONO (-3646 3125);
FORCEPROP 2 LAST CDS_LIB standard
J 0
(-3425 3125);
PAINT MONO (-3425 3125);
DISPLAY INVISIBLE (-3425 3125);
FORCEPROP 1 LAST OFFPAGE TRUE
J 0
(-3100 3000);
DISPLAY 0.872340 (-3100 3000);
DISPLAY INVISIBLE (-3100 3000);
FORCEPROP 1 LAST COMMENT_BODY TRUE
J 0
(-3300 3025);
DISPLAY 0.872340 (-3300 3025);
PAINT GREEN (-3300 3025);
DISPLAY INVISIBLE (-3300 3025);
FORCEPROP 2 LAST PATH I18
J 0
(-3375 3200);
DISPLAY 1.021277 (-3375 3200);
DISPLAY INVISIBLE (-3375 3200);
FORCEADD SCONN288_ADR50017P087CC..1
(-1675 2650);
FORCEPROP 1 LAST PART_NUMBER DFHST8FS460
J 0
(-2120 4660);
DISPLAY 0.723404 (-2120 4660);
PAINT GREEN (-2120 4660);
DISPLAY INVISIBLE (-2120 4660);
FORCEPROP 1 LAST MATERIAL IO
J 0
(-2120 4533);
DISPLAY 0.723404 (-2120 4533);
PAINT GREEN (-2120 4533);
FORCEPROP 2 LAST VALUE SCONN288_ADR50017-P087CC
J 0
(-2125 4775);
DISPLAY 1.021277 (-2125 4775);
FORCEPROP 2 LAST PART_TYPE SMLF
J 0
(-2125 4825);
DISPLAY 1.021277 (-2125 4825);
FORCEPROP 1 LAST $LOCATION J26
J 0
(-2125 4700);
DISPLAY 0.723404 (-2125 4700);
PAINT GREEN (-2125 4700);
FORCEPROP 0 LASTPIN (-2275 2025) $PN 62
J 2
(-2285 2035);
DISPLAY 0.680851 (-2285 2035);
PAINT MONO (-2285 2035);
FORCEPROP 0 LASTPIN (-2275 4075) $PN 66
J 2
(-2285 4085);
DISPLAY 0.680851 (-2285 4085);
PAINT MONO (-2285 4085);
FORCEPROP 0 LASTPIN (-2275 3675) $PN 76
J 2
(-2285 3685);
DISPLAY 0.680851 (-2285 3685);
PAINT MONO (-2285 3685);
FORCEPROP 0 LASTPIN (-2275 4125) $PN 211
J 2
(-2285 4135);
DISPLAY 0.680851 (-2285 4135);
PAINT MONO (-2285 4135);
FORCEPROP 0 LASTPIN (-2275 3725) $PN 221
J 2
(-2285 3735);
DISPLAY 0.680851 (-2285 3735);
PAINT MONO (-2285 3735);
FORCEPROP 0 LASTPIN (-2275 4175) $PN 68
J 2
(-2285 4185);
DISPLAY 0.680851 (-2285 4185);
PAINT MONO (-2285 4185);
FORCEPROP 0 LASTPIN (-2275 3775) $PN 78
J 2
(-2285 3785);
DISPLAY 0.680851 (-2285 3785);
PAINT MONO (-2285 3785);
FORCEPROP 0 LASTPIN (-2275 4225) $PN 213
J 2
(-2285 4235);
DISPLAY 0.680851 (-2285 4235);
PAINT MONO (-2285 4235);
FORCEPROP 0 LASTPIN (-2275 3825) $PN 223
J 2
(-2285 3835);
DISPLAY 0.680851 (-2285 3835);
PAINT MONO (-2285 3835);
FORCEPROP 0 LASTPIN (-2275 4275) $PN 70
J 2
(-2285 4285);
DISPLAY 0.680851 (-2285 4285);
PAINT MONO (-2285 4285);
FORCEPROP 0 LASTPIN (-2275 3875) $PN 80
J 2
(-2285 3885);
DISPLAY 0.680851 (-2285 3885);
PAINT MONO (-2285 3885);
FORCEPROP 0 LASTPIN (-2275 4325) $PN 215
J 2
(-2285 4335);
DISPLAY 0.680851 (-2285 4335);
PAINT MONO (-2285 4335);
FORCEPROP 0 LASTPIN (-2275 3925) $PN 225
J 2
(-2285 3935);
DISPLAY 0.680851 (-2285 3935);
PAINT MONO (-2285 3935);
FORCEPROP 0 LASTPIN (-2275 4375) $PN 72
J 2
(-2285 4385);
DISPLAY 0.680851 (-2285 4385);
PAINT MONO (-2285 4385);
FORCEPROP 0 LASTPIN (-2275 3975) $PN 82
J 2
(-2285 3985);
DISPLAY 0.680851 (-2285 3985);
PAINT MONO (-2285 3985);
FORCEPROP 0 LASTPIN (-2275 2625) $PN 51
J 2
(-2285 2635);
DISPLAY 0.680851 (-2285 2635);
PAINT MONO (-2285 2635);
FORCEPROP 0 LASTPIN (-2275 2175) $PN 96
J 2
(-2285 2185);
DISPLAY 0.680851 (-2285 2185);
PAINT MONO (-2285 2185);
FORCEPROP 0 LASTPIN (-2275 2675) $PN 53
J 2
(-2285 2685);
DISPLAY 0.680851 (-2285 2685);
PAINT MONO (-2285 2685);
FORCEPROP 0 LASTPIN (-2275 2225) $PN 98
J 2
(-2285 2235);
DISPLAY 0.680851 (-2285 2235);
PAINT MONO (-2285 2235);
FORCEPROP 0 LASTPIN (-2275 2725) $PN 196
J 2
(-2285 2735);
DISPLAY 0.680851 (-2285 2735);
PAINT MONO (-2285 2735);
FORCEPROP 0 LASTPIN (-2275 2275) $PN 241
J 2
(-2285 2285);
DISPLAY 0.680851 (-2285 2285);
PAINT MONO (-2285 2285);
FORCEPROP 0 LASTPIN (-2275 2775) $PN 198
J 2
(-2285 2785);
DISPLAY 0.680851 (-2285 2785);
PAINT MONO (-2285 2785);
FORCEPROP 0 LASTPIN (-2275 2325) $PN 243
J 2
(-2285 2335);
DISPLAY 0.680851 (-2285 2335);
PAINT MONO (-2285 2335);
FORCEPROP 0 LASTPIN (-2275 2825) $PN 58
J 2
(-2285 2835);
DISPLAY 0.680851 (-2285 2835);
PAINT MONO (-2285 2835);
FORCEPROP 0 LASTPIN (-2275 2375) $PN 89
J 2
(-2285 2385);
DISPLAY 0.680851 (-2285 2385);
PAINT MONO (-2285 2385);
FORCEPROP 0 LASTPIN (-2275 2875) $PN 60
J 2
(-2285 2885);
DISPLAY 0.680851 (-2285 2885);
PAINT MONO (-2285 2885);
FORCEPROP 0 LASTPIN (-2275 2425) $PN 91
J 2
(-2285 2435);
DISPLAY 0.680851 (-2285 2435);
PAINT MONO (-2285 2435);
FORCEPROP 0 LASTPIN (-2275 2925) $PN 203
J 2
(-2285 2935);
DISPLAY 0.680851 (-2285 2935);
PAINT MONO (-2285 2935);
FORCEPROP 0 LASTPIN (-2275 2475) $PN 234
J 2
(-2285 2485);
DISPLAY 0.680851 (-2285 2485);
PAINT MONO (-2285 2485);
FORCEPROP 0 LASTPIN (-2275 2975) $PN 205
J 2
(-2285 2985);
DISPLAY 0.680851 (-2285 2985);
PAINT MONO (-2285 2985);
FORCEPROP 0 LASTPIN (-2275 2525) $PN 236
J 2
(-2285 2535);
DISPLAY 0.680851 (-2285 2535);
PAINT MONO (-2285 2535);
FORCEPROP 0 LASTPIN (-2275 3075) $PN 218
J 2
(-2285 3085);
DISPLAY 0.680851 (-2285 3085);
PAINT MONO (-2285 3085);
FORCEPROP 0 LASTPIN (-2275 3125) $PN 217
J 2
(-2285 3135);
DISPLAY 0.680851 (-2285 3135);
PAINT MONO (-2285 3135);
FORCEPROP 0 LASTPIN (-2275 3375) $PN 64
J 2
(-2285 3385);
DISPLAY 0.680851 (-2285 3385);
PAINT MONO (-2285 3385);
FORCEPROP 0 LASTPIN (-2275 3225) $PN 84
J 2
(-2285 3235);
DISPLAY 0.680851 (-2285 3235);
PAINT MONO (-2285 3235);
FORCEPROP 0 LASTPIN (-2275 3425) $PN 209
J 2
(-2285 3435);
DISPLAY 0.680851 (-2285 3435);
PAINT MONO (-2285 3435);
FORCEPROP 0 LASTPIN (-2275 3275) $PN 229
J 2
(-2285 3285);
DISPLAY 0.680851 (-2285 3285);
PAINT MONO (-2285 3285);
FORCEPROP 0 LASTPIN (-1075 2825) $PN 7
J 0
(-1065 2835);
DISPLAY 0.680851 (-1065 2835);
PAINT MONO (-1065 2835);
FORCEPROP 0 LASTPIN (-1075 1175) $PN 100
J 0
(-1065 1185);
DISPLAY 0.680851 (-1065 1185);
PAINT MONO (-1065 1185);
FORCEPROP 0 LASTPIN (-1075 2875) $PN 9
J 0
(-1065 2885);
DISPLAY 0.680851 (-1065 2885);
PAINT MONO (-1065 2885);
FORCEPROP 0 LASTPIN (-1075 1225) $PN 102
J 0
(-1065 1235);
DISPLAY 0.680851 (-1065 1235);
PAINT MONO (-1065 1235);
FORCEPROP 0 LASTPIN (-1075 2925) $PN 152
J 0
(-1065 2935);
DISPLAY 0.680851 (-1065 2935);
PAINT MONO (-1065 2935);
FORCEPROP 0 LASTPIN (-1075 1275) $PN 245
J 0
(-1065 1285);
DISPLAY 0.680851 (-1065 1285);
PAINT MONO (-1065 1285);
FORCEPROP 0 LASTPIN (-1075 2975) $PN 154
J 0
(-1065 2985);
DISPLAY 0.680851 (-1065 2985);
PAINT MONO (-1065 2985);
FORCEPROP 0 LASTPIN (-1075 1325) $PN 247
J 0
(-1065 1335);
DISPLAY 0.680851 (-1065 1335);
PAINT MONO (-1065 1335);
FORCEPROP 0 LASTPIN (-1075 3025) $PN 14
J 0
(-1065 3035);
DISPLAY 0.680851 (-1065 3035);
PAINT MONO (-1065 3035);
FORCEPROP 0 LASTPIN (-1075 1375) $PN 107
J 0
(-1065 1385);
DISPLAY 0.680851 (-1065 1385);
PAINT MONO (-1065 1385);
FORCEPROP 0 LASTPIN (-1075 3075) $PN 16
J 0
(-1065 3085);
DISPLAY 0.680851 (-1065 3085);
PAINT MONO (-1065 3085);
FORCEPROP 0 LASTPIN (-1075 1425) $PN 109
J 0
(-1065 1435);
DISPLAY 0.680851 (-1065 1435);
PAINT MONO (-1065 1435);
FORCEPROP 0 LASTPIN (-1075 3125) $PN 159
J 0
(-1065 3135);
DISPLAY 0.680851 (-1065 3135);
PAINT MONO (-1065 3135);
FORCEPROP 0 LASTPIN (-1075 1475) $PN 252
J 0
(-1065 1485);
DISPLAY 0.680851 (-1065 1485);
PAINT MONO (-1065 1485);
FORCEPROP 0 LASTPIN (-1075 3175) $PN 161
J 0
(-1065 3185);
DISPLAY 0.680851 (-1065 3185);
PAINT MONO (-1065 3185);
FORCEPROP 0 LASTPIN (-1075 1525) $PN 254
J 0
(-1065 1535);
DISPLAY 0.680851 (-1065 1535);
PAINT MONO (-1065 1535);
FORCEPROP 0 LASTPIN (-1075 3225) $PN 18
J 0
(-1065 3235);
DISPLAY 0.680851 (-1065 3235);
PAINT MONO (-1065 3235);
FORCEPROP 0 LASTPIN (-1075 1575) $PN 111
J 0
(-1065 1585);
DISPLAY 0.680851 (-1065 1585);
PAINT MONO (-1065 1585);
FORCEPROP 0 LASTPIN (-1075 3275) $PN 20
J 0
(-1065 3285);
DISPLAY 0.680851 (-1065 3285);
PAINT MONO (-1065 3285);
FORCEPROP 0 LASTPIN (-1075 1625) $PN 113
J 0
(-1065 1635);
DISPLAY 0.680851 (-1065 1635);
PAINT MONO (-1065 1635);
FORCEPROP 0 LASTPIN (-1075 3325) $PN 163
J 0
(-1065 3335);
DISPLAY 0.680851 (-1065 3335);
PAINT MONO (-1065 3335);
FORCEPROP 0 LASTPIN (-1075 1675) $PN 256
J 0
(-1065 1685);
DISPLAY 0.680851 (-1065 1685);
PAINT MONO (-1065 1685);
FORCEPROP 0 LASTPIN (-1075 3375) $PN 165
J 0
(-1065 3385);
DISPLAY 0.680851 (-1065 3385);
PAINT MONO (-1065 3385);
FORCEPROP 0 LASTPIN (-1075 1725) $PN 258
J 0
(-1065 1735);
DISPLAY 0.680851 (-1065 1735);
PAINT MONO (-1065 1735);
FORCEPROP 0 LASTPIN (-1075 3425) $PN 25
J 0
(-1065 3435);
DISPLAY 0.680851 (-1065 3435);
PAINT MONO (-1065 3435);
FORCEPROP 0 LASTPIN (-1075 1775) $PN 118
J 0
(-1065 1785);
DISPLAY 0.680851 (-1065 1785);
PAINT MONO (-1065 1785);
FORCEPROP 0 LASTPIN (-1075 3475) $PN 27
J 0
(-1065 3485);
DISPLAY 0.680851 (-1065 3485);
PAINT MONO (-1065 3485);
FORCEPROP 0 LASTPIN (-1075 1825) $PN 120
J 0
(-1065 1835);
DISPLAY 0.680851 (-1065 1835);
PAINT MONO (-1065 1835);
FORCEPROP 0 LASTPIN (-1075 3525) $PN 170
J 0
(-1065 3535);
DISPLAY 0.680851 (-1065 3535);
PAINT MONO (-1065 3535);
FORCEPROP 0 LASTPIN (-1075 1875) $PN 263
J 0
(-1065 1885);
DISPLAY 0.680851 (-1065 1885);
PAINT MONO (-1065 1885);
FORCEPROP 0 LASTPIN (-1075 3575) $PN 172
J 0
(-1065 3585);
DISPLAY 0.680851 (-1065 3585);
PAINT MONO (-1065 3585);
FORCEPROP 0 LASTPIN (-1075 1925) $PN 265
J 0
(-1065 1935);
DISPLAY 0.680851 (-1065 1935);
PAINT MONO (-1065 1935);
FORCEPROP 0 LASTPIN (-1075 3625) $PN 29
J 0
(-1065 3635);
DISPLAY 0.680851 (-1065 3635);
PAINT MONO (-1065 3635);
FORCEPROP 0 LASTPIN (-1075 1975) $PN 122
J 0
(-1065 1985);
DISPLAY 0.680851 (-1065 1985);
PAINT MONO (-1065 1985);
FORCEPROP 0 LASTPIN (-1075 3675) $PN 31
J 0
(-1065 3685);
DISPLAY 0.680851 (-1065 3685);
PAINT MONO (-1065 3685);
FORCEPROP 0 LASTPIN (-1075 2025) $PN 124
J 0
(-1065 2035);
DISPLAY 0.680851 (-1065 2035);
PAINT MONO (-1065 2035);
FORCEPROP 0 LASTPIN (-1075 3725) $PN 174
J 0
(-1065 3735);
DISPLAY 0.680851 (-1065 3735);
PAINT MONO (-1065 3735);
FORCEPROP 0 LASTPIN (-1075 2075) $PN 267
J 0
(-1065 2085);
DISPLAY 0.680851 (-1065 2085);
PAINT MONO (-1065 2085);
FORCEPROP 0 LASTPIN (-1075 3775) $PN 176
J 0
(-1065 3785);
DISPLAY 0.680851 (-1065 3785);
PAINT MONO (-1065 3785);
FORCEPROP 0 LASTPIN (-1075 2125) $PN 269
J 0
(-1065 2135);
DISPLAY 0.680851 (-1065 2135);
PAINT MONO (-1065 2135);
FORCEPROP 0 LASTPIN (-1075 3825) $PN 36
J 0
(-1065 3835);
DISPLAY 0.680851 (-1065 3835);
PAINT MONO (-1065 3835);
FORCEPROP 0 LASTPIN (-1075 2175) $PN 129
J 0
(-1065 2185);
DISPLAY 0.680851 (-1065 2185);
PAINT MONO (-1065 2185);
FORCEPROP 0 LASTPIN (-1075 3875) $PN 38
J 0
(-1065 3885);
DISPLAY 0.680851 (-1065 3885);
PAINT MONO (-1065 3885);
FORCEPROP 0 LASTPIN (-1075 2225) $PN 131
J 0
(-1065 2235);
DISPLAY 0.680851 (-1065 2235);
PAINT MONO (-1065 2235);
FORCEPROP 0 LASTPIN (-1075 3925) $PN 181
J 0
(-1065 3935);
DISPLAY 0.680851 (-1065 3935);
PAINT MONO (-1065 3935);
FORCEPROP 0 LASTPIN (-1075 2275) $PN 274
J 0
(-1065 2285);
DISPLAY 0.680851 (-1065 2285);
PAINT MONO (-1065 2285);
FORCEPROP 0 LASTPIN (-1075 3975) $PN 183
J 0
(-1065 3985);
DISPLAY 0.680851 (-1065 3985);
PAINT MONO (-1065 3985);
FORCEPROP 0 LASTPIN (-1075 2325) $PN 276
J 0
(-1065 2335);
DISPLAY 0.680851 (-1065 2335);
PAINT MONO (-1065 2335);
FORCEPROP 0 LASTPIN (-1075 4025) $PN 40
J 0
(-1065 4035);
DISPLAY 0.680851 (-1065 4035);
PAINT MONO (-1065 4035);
FORCEPROP 0 LASTPIN (-1075 2375) $PN 133
J 0
(-1065 2385);
DISPLAY 0.680851 (-1065 2385);
PAINT MONO (-1065 2385);
FORCEPROP 0 LASTPIN (-1075 4075) $PN 42
J 0
(-1065 4085);
DISPLAY 0.680851 (-1065 4085);
PAINT MONO (-1065 4085);
FORCEPROP 0 LASTPIN (-1075 2425) $PN 135
J 0
(-1065 2435);
DISPLAY 0.680851 (-1065 2435);
PAINT MONO (-1065 2435);
FORCEPROP 0 LASTPIN (-1075 4125) $PN 185
J 0
(-1065 4135);
DISPLAY 0.680851 (-1065 4135);
PAINT MONO (-1065 4135);
FORCEPROP 0 LASTPIN (-1075 2475) $PN 278
J 0
(-1065 2485);
DISPLAY 0.680851 (-1065 2485);
PAINT MONO (-1065 2485);
FORCEPROP 0 LASTPIN (-1075 4175) $PN 187
J 0
(-1065 4185);
DISPLAY 0.680851 (-1065 4185);
PAINT MONO (-1065 4185);
FORCEPROP 0 LASTPIN (-1075 2525) $PN 280
J 0
(-1065 2535);
DISPLAY 0.680851 (-1065 2535);
PAINT MONO (-1065 2535);
FORCEPROP 0 LASTPIN (-1075 4225) $PN 47
J 0
(-1065 4235);
DISPLAY 0.680851 (-1065 4235);
PAINT MONO (-1065 4235);
FORCEPROP 0 LASTPIN (-1075 2575) $PN 140
J 0
(-1065 2585);
DISPLAY 0.680851 (-1065 2585);
PAINT MONO (-1065 2585);
FORCEPROP 0 LASTPIN (-1075 4275) $PN 49
J 0
(-1065 4285);
DISPLAY 0.680851 (-1065 4285);
PAINT MONO (-1065 4285);
FORCEPROP 0 LASTPIN (-1075 2625) $PN 142
J 0
(-1065 2635);
DISPLAY 0.680851 (-1065 2635);
PAINT MONO (-1065 2635);
FORCEPROP 0 LASTPIN (-1075 4325) $PN 192
J 0
(-1065 4335);
DISPLAY 0.680851 (-1065 4335);
PAINT MONO (-1065 4335);
FORCEPROP 0 LASTPIN (-1075 2675) $PN 285
J 0
(-1065 2685);
DISPLAY 0.680851 (-1065 2685);
PAINT MONO (-1065 2685);
FORCEPROP 0 LASTPIN (-1075 4375) $PN 194
J 0
(-1065 4385);
DISPLAY 0.680851 (-1065 4385);
PAINT MONO (-1065 4385);
FORCEPROP 0 LASTPIN (-1075 2725) $PN 287
J 0
(-1065 2735);
DISPLAY 0.680851 (-1065 2735);
PAINT MONO (-1065 2735);
FORCEPROP 0 LASTPIN (-2275 1875) $PN 148
J 2
(-2285 1885);
DISPLAY 0.680851 (-2285 1885);
PAINT MONO (-2285 1885);
FORCEPROP 0 LASTPIN (-2275 1775) $PN 4
J 2
(-2285 1785);
DISPLAY 0.680851 (-2285 1785);
PAINT MONO (-2285 1785);
FORCEPROP 0 LASTPIN (-2275 1825) $PN 5
J 2
(-2285 1835);
DISPLAY 0.680851 (-2285 1835);
PAINT MONO (-2285 1835);
FORCEPROP 0 LASTPIN (-2275 975) $PN 86
J 2
(-2285 985);
DISPLAY 0.680851 (-2285 985);
PAINT MONO (-2285 985);
FORCEPROP 0 LASTPIN (-2275 925) $PN 87
J 2
(-2285 935);
DISPLAY 0.680851 (-2285 935);
PAINT MONO (-2285 935);
FORCEPROP 0 LASTPIN (-2275 3575) $PN 74
J 2
(-2285 3585);
DISPLAY 0.680851 (-2285 3585);
PAINT MONO (-2285 3585);
FORCEPROP 0 LASTPIN (-2275 3525) $PN 227
J 2
(-2285 3535);
DISPLAY 0.680851 (-2285 3535);
PAINT MONO (-2285 3535);
FORCEPROP 0 LASTPIN (-2275 1525) $PN 147
J 2
(-2285 1535);
DISPLAY 0.680851 (-2285 1535);
PAINT MONO (-2285 1535);
FORCEPROP 0 LASTPIN (-2275 2075) $PN 207
J 2
(-2285 2085);
DISPLAY 0.680851 (-2285 2085);
PAINT MONO (-2285 2085);
FORCEPROP 0 LASTPIN (-2275 1125) $PN 2
J 2
(-2285 1135);
DISPLAY 0.680851 (-2285 1135);
PAINT MONO (-2285 1135);
FORCEPROP 0 LASTPIN (-2275 1175) $PN 144
J 2
(-2285 1185);
DISPLAY 0.680851 (-2285 1185);
PAINT MONO (-2285 1185);
FORCEPROP 0 LASTPIN (-2275 1225) $PN 149
J 2
(-2285 1235);
DISPLAY 0.680851 (-2285 1235);
PAINT MONO (-2285 1235);
FORCEPROP 0 LASTPIN (-2275 1275) $PN 150
J 2
(-2285 1285);
DISPLAY 0.680851 (-2285 1285);
PAINT MONO (-2285 1285);
FORCEPROP 0 LASTPIN (-2275 1325) $PN 220
J 2
(-2285 1335);
DISPLAY 0.680851 (-2285 1335);
PAINT MONO (-2285 1335);
FORCEPROP 0 LASTPIN (-2275 1375) $PN 231
J 2
(-2285 1385);
DISPLAY 0.680851 (-2285 1385);
PAINT MONO (-2285 1385);
FORCEPROP 0 LASTPIN (-2275 1425) $PN 232
J 2
(-2285 1435);
DISPLAY 0.680851 (-2285 1435);
PAINT MONO (-2285 1435);
FORCEPROP 0 LASTPIN (-2275 1925) $PN 3
J 2
(-2285 1935);
DISPLAY 0.680851 (-2285 1935);
PAINT MONO (-2285 1935);
FORCEPROP 1 LAST NEEDS_NO_SIZE TRUE
J 0
(-1675 2650);
DISPLAY 0.723404 (-1675 2650);
PAINT GREEN (-1675 2650);
DISPLAY INVISIBLE (-1675 2650);
FORCEPROP 1 LAST CDS_LMAN_SYM_OUTLINE -450,1875,450,-1875
J 0
(-1675 2650);
DISPLAY 0.468085 (-1675 2650);
PAINT GREEN (-1675 2650);
DISPLAY INVISIBLE (-1675 2650);
FORCEPROP 2 LAST CDS_LIB pure_quanta
J 0
(-1675 2650);
DISPLAY INVISIBLE (-1675 2650);
FORCEPROP 1 LAST PATH I180
J 0
(-1675 2650);
DISPLAY 0.723404 (-1675 2650);
PAINT GREEN (-1675 2650);
DISPLAY INVISIBLE (-1675 2650);
FORCEPROP 2 LAST CDS_LOCATION J26
J 0
(-2125 4875);
DISPLAY 1.021277 (-2125 4875);
DISPLAY INVISIBLE (-2125 4875);
FORCEPROP 0 LAST $SEC 1
J 0
(-2125 4875);
DISPLAY 0.680851 (-2125 4875);
PAINT MONO (-2125 4875);
DISPLAY INVISIBLE (-2125 4875);
FORCEPROP 2 LAST CDS_SEC 1
J 0
(-2125 4875);
DISPLAY 1.021277 (-2125 4875);
DISPLAY INVISIBLE (-2125 4875);
FORCEADD SCONN288_ADR50017P087CC..2
(1000 3375);
FORCEPROP 1 LAST PART_NUMBER DFHST8FS460
J 0
(395 4663);
DISPLAY 0.723404 (395 4663);
PAINT GREEN (395 4663);
DISPLAY INVISIBLE (395 4663);
FORCEPROP 2 LAST PART_TYPE SMLF
J 0
(400 4900);
DISPLAY 1.021277 (400 4900);
FORCEPROP 1 LAST MATERIAL IO
J 0
(395 4536);
DISPLAY 0.723404 (395 4536);
PAINT GREEN (395 4536);
FORCEPROP 2 LAST VALUE SCONN288_ADR50017-P087CC
J 0
(400 4850);
DISPLAY 1.021277 (400 4850);
FORCEPROP 1 LAST LOCATION J26
J 0
(395 4810);
DISPLAY 0.723404 (395 4810);
PAINT GREEN (395 4810);
FORCEPROP 0 LASTPIN (1750 3425) $PN 12
J 0
(1760 3435);
DISPLAY 0.680851 (1760 3435);
PAINT MONO (1760 3435);
FORCEPROP 0 LASTPIN (1750 3475) $PN 11
J 0
(1760 3485);
DISPLAY 0.680851 (1760 3485);
PAINT MONO (1760 3485);
FORCEPROP 0 LASTPIN (1750 2375) $PN 105
J 0
(1760 2385);
DISPLAY 0.680851 (1760 2385);
PAINT MONO (1760 2385);
FORCEPROP 0 LASTPIN (1750 2425) $PN 104
J 0
(1760 2435);
DISPLAY 0.680851 (1760 2435);
PAINT MONO (1760 2435);
FORCEPROP 0 LASTPIN (1750 3525) $PN 23
J 0
(1760 3535);
DISPLAY 0.680851 (1760 3535);
PAINT MONO (1760 3535);
FORCEPROP 0 LASTPIN (1750 3575) $PN 22
J 0
(1760 3585);
DISPLAY 0.680851 (1760 3585);
PAINT MONO (1760 3585);
FORCEPROP 0 LASTPIN (1750 2475) $PN 116
J 0
(1760 2485);
DISPLAY 0.680851 (1760 2485);
PAINT MONO (1760 2485);
FORCEPROP 0 LASTPIN (1750 2525) $PN 115
J 0
(1760 2535);
DISPLAY 0.680851 (1760 2535);
PAINT MONO (1760 2535);
FORCEPROP 0 LASTPIN (1750 3625) $PN 34
J 0
(1760 3635);
DISPLAY 0.680851 (1760 3635);
PAINT MONO (1760 3635);
FORCEPROP 0 LASTPIN (1750 3675) $PN 33
J 0
(1760 3685);
DISPLAY 0.680851 (1760 3685);
PAINT MONO (1760 3685);
FORCEPROP 0 LASTPIN (1750 2575) $PN 127
J 0
(1760 2585);
DISPLAY 0.680851 (1760 2585);
PAINT MONO (1760 2585);
FORCEPROP 0 LASTPIN (1750 2625) $PN 126
J 0
(1760 2635);
DISPLAY 0.680851 (1760 2635);
PAINT MONO (1760 2635);
FORCEPROP 0 LASTPIN (1750 3725) $PN 45
J 0
(1760 3735);
DISPLAY 0.680851 (1760 3735);
PAINT MONO (1760 3735);
FORCEPROP 0 LASTPIN (1750 3775) $PN 44
J 0
(1760 3785);
DISPLAY 0.680851 (1760 3785);
PAINT MONO (1760 3785);
FORCEPROP 0 LASTPIN (1750 2675) $PN 138
J 0
(1760 2685);
DISPLAY 0.680851 (1760 2685);
PAINT MONO (1760 2685);
FORCEPROP 0 LASTPIN (1750 2725) $PN 137
J 0
(1760 2735);
DISPLAY 0.680851 (1760 2735);
PAINT MONO (1760 2735);
FORCEPROP 0 LASTPIN (1750 3825) $PN 56
J 0
(1760 3835);
DISPLAY 0.680851 (1760 3835);
PAINT MONO (1760 3835);
FORCEPROP 0 LASTPIN (1750 3875) $PN 55
J 0
(1760 3885);
DISPLAY 0.680851 (1760 3885);
PAINT MONO (1760 3885);
FORCEPROP 0 LASTPIN (1750 2775) $PN 238
J 0
(1760 2785);
DISPLAY 0.680851 (1760 2785);
PAINT MONO (1760 2785);
FORCEPROP 0 LASTPIN (1750 2825) $PN 239
J 0
(1760 2835);
DISPLAY 0.680851 (1760 2835);
PAINT MONO (1760 2835);
FORCEPROP 0 LASTPIN (1750 3925) $PN 156
J 0
(1760 3935);
DISPLAY 0.680851 (1760 3935);
PAINT MONO (1760 3935);
FORCEPROP 0 LASTPIN (1750 3975) $PN 157
J 0
(1760 3985);
DISPLAY 0.680851 (1760 3985);
PAINT MONO (1760 3985);
FORCEPROP 0 LASTPIN (1750 2875) $PN 249
J 0
(1760 2885);
DISPLAY 0.680851 (1760 2885);
PAINT MONO (1760 2885);
FORCEPROP 0 LASTPIN (1750 2925) $PN 250
J 0
(1760 2935);
DISPLAY 0.680851 (1760 2935);
PAINT MONO (1760 2935);
FORCEPROP 0 LASTPIN (1750 4025) $PN 167
J 0
(1760 4035);
DISPLAY 0.680851 (1760 4035);
PAINT MONO (1760 4035);
FORCEPROP 0 LASTPIN (1750 4075) $PN 168
J 0
(1760 4085);
DISPLAY 0.680851 (1760 4085);
PAINT MONO (1760 4085);
FORCEPROP 0 LASTPIN (1750 2975) $PN 260
J 0
(1760 2985);
DISPLAY 0.680851 (1760 2985);
PAINT MONO (1760 2985);
FORCEPROP 0 LASTPIN (1750 3025) $PN 261
J 0
(1760 3035);
DISPLAY 0.680851 (1760 3035);
PAINT MONO (1760 3035);
FORCEPROP 0 LASTPIN (1750 4125) $PN 178
J 0
(1760 4135);
DISPLAY 0.680851 (1760 4135);
PAINT MONO (1760 4135);
FORCEPROP 0 LASTPIN (1750 4175) $PN 179
J 0
(1760 4185);
DISPLAY 0.680851 (1760 4185);
PAINT MONO (1760 4185);
FORCEPROP 0 LASTPIN (1750 3075) $PN 271
J 0
(1760 3085);
DISPLAY 0.680851 (1760 3085);
PAINT MONO (1760 3085);
FORCEPROP 0 LASTPIN (1750 3125) $PN 272
J 0
(1760 3135);
DISPLAY 0.680851 (1760 3135);
PAINT MONO (1760 3135);
FORCEPROP 0 LASTPIN (1750 4225) $PN 189
J 0
(1760 4235);
DISPLAY 0.680851 (1760 4235);
PAINT MONO (1760 4235);
FORCEPROP 0 LASTPIN (1750 4275) $PN 190
J 0
(1760 4285);
DISPLAY 0.680851 (1760 4285);
PAINT MONO (1760 4285);
FORCEPROP 0 LASTPIN (1750 3175) $PN 282
J 0
(1760 3185);
DISPLAY 0.680851 (1760 3185);
PAINT MONO (1760 3185);
FORCEPROP 0 LASTPIN (1750 3225) $PN 283
J 0
(1760 3235);
DISPLAY 0.680851 (1760 3235);
PAINT MONO (1760 3235);
FORCEPROP 0 LASTPIN (1750 4325) $PN 200
J 0
(1760 4335);
DISPLAY 0.680851 (1760 4335);
PAINT MONO (1760 4335);
FORCEPROP 0 LASTPIN (1750 4375) $PN 201
J 0
(1760 4385);
DISPLAY 0.680851 (1760 4385);
PAINT MONO (1760 4385);
FORCEPROP 0 LASTPIN (1750 3275) $PN 94
J 0
(1760 3285);
DISPLAY 0.680851 (1760 3285);
PAINT MONO (1760 3285);
FORCEPROP 0 LASTPIN (1750 3325) $PN 93
J 0
(1760 3335);
DISPLAY 0.680851 (1760 3335);
PAINT MONO (1760 3335);
FORCEPROP 1 LAST NEEDS_NO_SIZE TRUE
J 0
(1000 3375);
DISPLAY 0.723404 (1000 3375);
PAINT GREEN (1000 3375);
DISPLAY INVISIBLE (1000 3375);
FORCEPROP 1 LAST CDS_LMAN_SYM_OUTLINE -600,1150,600,-1150
J 0
(1000 3375);
DISPLAY 0.468085 (1000 3375);
PAINT GREEN (1000 3375);
DISPLAY INVISIBLE (1000 3375);
FORCEPROP 2 LAST CDS_LIB pure_quanta
J 0
(1000 3375);
DISPLAY INVISIBLE (1000 3375);
FORCEPROP 1 LAST PATH I181
J 0
(1000 3375);
DISPLAY 0.723404 (1000 3375);
PAINT GREEN (1000 3375);
DISPLAY INVISIBLE (1000 3375);
FORCEPROP 0 LAST $SEC 2
J 0
(400 4950);
DISPLAY 0.680851 (400 4950);
PAINT MONO (400 4950);
DISPLAY INVISIBLE (400 4950);
FORCEPROP 0 LAST CDS_SEC 2
J 0
(400 4950);
DISPLAY 1.021277 (400 4950);
DISPLAY INVISIBLE (400 4950);
FORCEADD OFFPAGE..1
(-2275 1625);
FORCEPROP 2 LAST $XR7 113 
J 0
(-3367 1625);
DISPLAY 0.638298 (-3367 1625);
PAINT MONO (-3367 1625);
FORCEPROP 2 LAST $XR6 112 
J 0
(-3247 1625);
DISPLAY 0.638298 (-3247 1625);
PAINT MONO (-3247 1625);
FORCEPROP 2 LAST $XR5 111 
J 0
(-3127 1625);
DISPLAY 0.638298 (-3127 1625);
PAINT MONO (-3127 1625);
FORCEPROP 2 LAST $XR4 110 
J 0
(-3007 1625);
DISPLAY 0.638298 (-3007 1625);
PAINT MONO (-3007 1625);
FORCEPROP 2 LAST $XR3 109 
J 0
(-2887 1625);
DISPLAY 0.638298 (-2887 1625);
PAINT MONO (-2887 1625);
FORCEPROP 2 LAST $XR2 108 
J 0
(-2767 1625);
DISPLAY 0.638298 (-2767 1625);
PAINT MONO (-2767 1625);
FORCEPROP 2 LAST $XR1 106 
J 0
(-2647 1625);
DISPLAY 0.638298 (-2647 1625);
PAINT MONO (-2647 1625);
FORCEPROP 2 LAST $XR0 230 
J 0
(-2527 1625);
DISPLAY 0.638298 (-2527 1625);
PAINT MONO (-2527 1625);
FORCEPROP 2 LAST CDS_LIB standard
J 2
(-2275 1625);
DISPLAY INVISIBLE (-2275 1625);
FORCEPROP 1 LAST OFFPAGE TRUE
J 0
(-1950 1500);
DISPLAY 0.872340 (-1950 1500);
DISPLAY INVISIBLE (-1950 1500);
FORCEPROP 1 LAST COMMENT_BODY TRUE
J 0
(-2150 1525);
DISPLAY 0.872340 (-2150 1525);
PAINT GREEN (-2150 1525);
DISPLAY INVISIBLE (-2150 1525);
FORCEPROP 2 LAST PATH I182
J 2
(-2450 1700);
DISPLAY 1.021277 (-2450 1700);
DISPLAY INVISIBLE (-2450 1700);
FORCEADD Q_RES..1
(-3500 1675);
FORCEPROP 1 LAST PART_NUMBER CS04992FB07
J 0
(-3400 1650);
DISPLAY 0.404255 (-3400 1650);
DISPLAY INVISIBLE (-3400 1650);
FORCEPROP 1 LAST VALUE 49.9
J 2
(-3275 1675);
DISPLAY 0.510638 (-3275 1675);
FORCEPROP 1 LAST MATERIAL CHIP
J 0
(-3625 1650);
DISPLAY 0.404255 (-3625 1650);
FORCEPROP 1 LAST $LOCATION R3900
J 0
(-3750 1675);
DISPLAY 0.638298 (-3750 1675);
FORCEPROP 1 LASTPIN (-3600 1675) $PN 1
J 0
(-3588 1687);
DISPLAY 0.787234 (-3588 1687);
PAINT MONO (-3588 1687);
FORCEPROP 1 LASTPIN (-3400 1675) $PN 2
J 0
(-3438 1687);
DISPLAY 0.787234 (-3438 1687);
PAINT MONO (-3438 1687);
FORCEPROP 2 LAST CDS_LIB pure_quanta
J 0
(-3500 1675);
DISPLAY INVISIBLE (-3500 1675);
FORCEPROP 1 LAST PACK_TYPE 0402LF
J 0
(-3200 1675);
DISPLAY 0.510638 (-3200 1675);
DISPLAY INVISIBLE (-3200 1675);
FORCEPROP 1 LAST TOLERANCE 1%
J 0
(-3275 1675);
DISPLAY 0.510638 (-3275 1675);
DISPLAY INVISIBLE (-3275 1675);
FORCEPROP 1 LAST WATTAGE 1/16W
J 2
(-3200 1625);
DISPLAY 0.404255 (-3200 1625);
DISPLAY INVISIBLE (-3200 1625);
FORCEPROP 1 LAST PATH I183
J 0
(-3550 1825);
DISPLAY 0.978723 (-3550 1825);
PAINT WHITE (-3550 1825);
DISPLAY INVISIBLE (-3550 1825);
FORCEPROP 0 LAST CDS_LOCATION R3900
J 0
(-3650 1725);
DISPLAY 1.021277 (-3650 1725);
DISPLAY INVISIBLE (-3650 1725);
FORCEPROP 0 LAST $SEC 1
J 0
(-3650 1725);
DISPLAY 0.680851 (-3650 1725);
PAINT MONO (-3650 1725);
DISPLAY INVISIBLE (-3650 1725);
FORCEPROP 0 LAST CDS_SEC 1
J 0
(-3650 1725);
DISPLAY 1.021277 (-3650 1725);
DISPLAY INVISIBLE (-3650 1725);
FORCEADD OFFPAGE..1
(-3425 3525);
FORCEPROP 2 LAST $XR1 106 
J 0
(-3766 3525);
DISPLAY 0.638298 (-3766 3525);
PAINT MONO (-3766 3525);
FORCEPROP 2 LAST $XR0 55 
J 0
(-3646 3525);
DISPLAY 0.638298 (-3646 3525);
PAINT MONO (-3646 3525);
FORCEPROP 2 LAST CDS_LIB standard
J 0
(-3425 3525);
PAINT MONO (-3425 3525);
DISPLAY INVISIBLE (-3425 3525);
FORCEPROP 1 LAST OFFPAGE TRUE
J 0
(-3100 3400);
DISPLAY 0.872340 (-3100 3400);
DISPLAY INVISIBLE (-3100 3400);
FORCEPROP 1 LAST COMMENT_BODY TRUE
J 0
(-3300 3425);
DISPLAY 0.872340 (-3300 3425);
PAINT GREEN (-3300 3425);
DISPLAY INVISIBLE (-3300 3425);
FORCEPROP 2 LAST PATH I19
J 0
(-3375 3600);
DISPLAY 1.021277 (-3375 3600);
DISPLAY INVISIBLE (-3375 3600);
FORCEADD Q_RES..2
(-2275 225);
FORCEPROP 1 LAST PART_NUMBER CS31542FB02
J 0
(-2235 100);
DISPLAY 0.978723 (-2235 100);
DISPLAY INVISIBLE (-2235 100);
FORCEPROP 1 LAST PACK_TYPE 0402LF
J 0
(-2235 50);
DISPLAY 0.978723 (-2235 50);
FORCEPROP 1 LAST WATTAGE 1/16W
J 0
(-2235 200);
DISPLAY 0.978723 (-2235 200);
FORCEPROP 1 LAST MATERIAL CHIP
J 0
(-2235 150);
DISPLAY 0.978723 (-2235 150);
FORCEPROP 1 LAST TOLERANCE 1%
J 0
(-2230 250);
DISPLAY 0.978723 (-2230 250);
FORCEPROP 1 LAST VALUE 15.4K
J 0
(-2230 300);
DISPLAY 0.978723 (-2230 300);
FORCEPROP 1 LAST $LOCATION R78
J 0
(-2230 350);
DISPLAY 0.978723 (-2230 350);
FORCEPROP 1 LASTPIN (-2275 325) $PN 1
J 0
(-2270 287);
DISPLAY 0.787234 (-2270 287);
PAINT MONO (-2270 287);
FORCEPROP 1 LASTPIN (-2275 125) $PN 2
J 0
(-2270 135);
DISPLAY 0.787234 (-2270 135);
PAINT MONO (-2270 135);
FORCEPROP 2 LAST CDS_LIB pure_quanta
J 0
(-2275 225);
DISPLAY INVISIBLE (-2275 225);
FORCEPROP 1 LAST PATH I2
J 0
(-2225 400);
DISPLAY 0.978723 (-2225 400);
PAINT WHITE (-2225 400);
DISPLAY INVISIBLE (-2225 400);
FORCEPROP 2 LAST CDS_LOCATION R78
J 0
(-2225 450);
DISPLAY 1.021277 (-2225 450);
DISPLAY INVISIBLE (-2225 450);
FORCEPROP 0 LAST $SEC 1
J 0
(-2225 400);
DISPLAY 0.680851 (-2225 400);
PAINT MONO (-2225 400);
DISPLAY INVISIBLE (-2225 400);
FORCEPROP 2 LAST CDS_SEC 1
J 0
(-2225 450);
DISPLAY 1.021277 (-2225 450);
DISPLAY INVISIBLE (-2225 450);
FORCEADD OFFPAGE..1
(-3425 3375);
FORCEPROP 2 LAST $XR0 55 
J 0
(-3646 3375);
DISPLAY 0.638298 (-3646 3375);
PAINT MONO (-3646 3375);
FORCEPROP 2 LAST CDS_LIB standard
J 0
(-3425 3375);
PAINT MONO (-3425 3375);
DISPLAY INVISIBLE (-3425 3375);
FORCEPROP 1 LAST OFFPAGE TRUE
J 0
(-3100 3250);
DISPLAY 0.872340 (-3100 3250);
DISPLAY INVISIBLE (-3100 3250);
FORCEPROP 1 LAST COMMENT_BODY TRUE
J 0
(-3300 3275);
DISPLAY 0.872340 (-3300 3275);
PAINT GREEN (-3300 3275);
DISPLAY INVISIBLE (-3300 3275);
FORCEPROP 2 LAST PATH I20
J 0
(-3375 3450);
DISPLAY 1.021277 (-3375 3450);
DISPLAY INVISIBLE (-3375 3450);
FORCEADD OFFPAGE..1
(-3425 3425);
FORCEPROP 2 LAST $XR0 55 
J 0
(-3646 3425);
DISPLAY 0.638298 (-3646 3425);
PAINT MONO (-3646 3425);
FORCEPROP 2 LAST CDS_LIB standard
J 0
(-3425 3425);
PAINT MONO (-3425 3425);
DISPLAY INVISIBLE (-3425 3425);
FORCEPROP 1 LAST OFFPAGE TRUE
J 0
(-3100 3300);
DISPLAY 0.872340 (-3100 3300);
DISPLAY INVISIBLE (-3100 3300);
FORCEPROP 1 LAST COMMENT_BODY TRUE
J 0
(-3300 3325);
DISPLAY 0.872340 (-3300 3325);
PAINT GREEN (-3300 3325);
DISPLAY INVISIBLE (-3300 3325);
FORCEPROP 2 LAST PATH I21
J 0
(-3375 3500);
DISPLAY 1.021277 (-3375 3500);
DISPLAY INVISIBLE (-3375 3500);
FORCEADD OFFPAGE..1
(-3425 3575);
FORCEPROP 2 LAST $XR1 106 
J 0
(-3766 3575);
DISPLAY 0.638298 (-3766 3575);
PAINT MONO (-3766 3575);
FORCEPROP 2 LAST $XR0 55 
J 0
(-3646 3575);
DISPLAY 0.638298 (-3646 3575);
PAINT MONO (-3646 3575);
FORCEPROP 2 LAST CDS_LIB standard
J 0
(-3425 3575);
PAINT MONO (-3425 3575);
DISPLAY INVISIBLE (-3425 3575);
FORCEPROP 1 LAST OFFPAGE TRUE
J 0
(-3100 3450);
DISPLAY 0.872340 (-3100 3450);
DISPLAY INVISIBLE (-3100 3450);
FORCEPROP 1 LAST COMMENT_BODY TRUE
J 0
(-3300 3475);
DISPLAY 0.872340 (-3300 3475);
PAINT GREEN (-3300 3475);
DISPLAY INVISIBLE (-3300 3475);
FORCEPROP 2 LAST PATH I22
J 0
(-3375 3650);
DISPLAY 1.021277 (-3375 3650);
DISPLAY INVISIBLE (-3375 3650);
FORCEADD OFFPAGE..1
(-3425 4000);
FORCEPROP 2 LAST $XR1 106 
J 0
(-3766 4000);
DISPLAY 0.638298 (-3766 4000);
PAINT MONO (-3766 4000);
FORCEPROP 2 LAST $XR0 55 
J 0
(-3646 4000);
DISPLAY 0.638298 (-3646 4000);
PAINT MONO (-3646 4000);
FORCEPROP 2 LAST CDS_LIB standard
J 0
(-3425 4000);
PAINT MONO (-3425 4000);
DISPLAY INVISIBLE (-3425 4000);
FORCEPROP 1 LAST OFFPAGE TRUE
J 0
(-3100 3875);
DISPLAY 0.872340 (-3100 3875);
DISPLAY INVISIBLE (-3100 3875);
FORCEPROP 1 LAST COMMENT_BODY TRUE
J 0
(-3300 3900);
DISPLAY 0.872340 (-3300 3900);
PAINT GREEN (-3300 3900);
DISPLAY INVISIBLE (-3300 3900);
FORCEPROP 2 LAST PATH I23
J 0
(-3375 4075);
DISPLAY 1.021277 (-3375 4075);
DISPLAY INVISIBLE (-3375 4075);
FORCEADD TAP..1
R 2
(-2500 2175);
FORCEPROP 3 LASTPIN (-2450 2175) SIG_NAME M_E_CPU1_SB_CB<0>
J 0
(-2440 2185);
DISPLAY 0.659574 (-2440 2185);
PAINT MONO (-2440 2185);
DISPLAY INVISIBLE (-2440 2185);
FORCEPROP 1 LASTPIN (-2450 2175) BN 0
J 2
(-2438 2183);
DISPLAY 0.680851 (-2438 2183);
PAINT GREEN (-2438 2183);
FORCEPROP 2 LAST CDS_LIB standard
J 0
(-2500 2175);
PAINT MONO (-2500 2175);
DISPLAY INVISIBLE (-2500 2175);
FORCEPROP 1 LAST BODY_TYPE PLUMBING
J 2
(-2500 2225);
DISPLAY 0.872340 (-2500 2225);
PAINT GREEN (-2500 2225);
DISPLAY INVISIBLE (-2500 2225);
FORCEPROP 1 LAST HDL_TAP TRUE
J 2
(-2825 2050);
DISPLAY 0.872340 (-2825 2050);
DISPLAY INVISIBLE (-2825 2050);
FORCEPROP 1 LAST PATH I25
J 2
(-2498 2175);
DISPLAY 0.872340 (-2498 2175);
PAINT GREEN (-2498 2175);
DISPLAY INVISIBLE (-2498 2175);
FORCEADD TAP..1
R 2
(-2500 2225);
FORCEPROP 3 LASTPIN (-2450 2225) SIG_NAME M_E_CPU1_SB_CB<1>
J 0
(-2440 2235);
DISPLAY 0.659574 (-2440 2235);
PAINT MONO (-2440 2235);
DISPLAY INVISIBLE (-2440 2235);
FORCEPROP 1 LASTPIN (-2450 2225) BN 1
J 2
(-2438 2233);
DISPLAY 0.680851 (-2438 2233);
PAINT GREEN (-2438 2233);
FORCEPROP 2 LAST CDS_LIB standard
J 0
(-2500 2225);
DISPLAY INVISIBLE (-2500 2225);
FORCEPROP 1 LAST BODY_TYPE PLUMBING
J 2
(-2500 2275);
DISPLAY 0.872340 (-2500 2275);
PAINT GREEN (-2500 2275);
DISPLAY INVISIBLE (-2500 2275);
FORCEPROP 1 LAST HDL_TAP TRUE
J 2
(-2825 2100);
DISPLAY 0.872340 (-2825 2100);
DISPLAY INVISIBLE (-2825 2100);
FORCEPROP 1 LAST PATH I26
J 2
(-2498 2225);
DISPLAY 0.872340 (-2498 2225);
PAINT GREEN (-2498 2225);
DISPLAY INVISIBLE (-2498 2225);
FORCEADD TAP..1
R 2
(-2500 2275);
FORCEPROP 3 LASTPIN (-2450 2275) SIG_NAME M_E_CPU1_SB_CB<2>
J 0
(-2440 2285);
DISPLAY 0.659574 (-2440 2285);
PAINT MONO (-2440 2285);
DISPLAY INVISIBLE (-2440 2285);
FORCEPROP 1 LASTPIN (-2450 2275) BN 2
J 2
(-2438 2283);
DISPLAY 0.680851 (-2438 2283);
PAINT GREEN (-2438 2283);
FORCEPROP 2 LAST CDS_LIB standard
J 0
(-2500 2275);
DISPLAY INVISIBLE (-2500 2275);
FORCEPROP 1 LAST BODY_TYPE PLUMBING
J 2
(-2500 2325);
DISPLAY 0.872340 (-2500 2325);
PAINT GREEN (-2500 2325);
DISPLAY INVISIBLE (-2500 2325);
FORCEPROP 1 LAST HDL_TAP TRUE
J 2
(-2825 2150);
DISPLAY 0.872340 (-2825 2150);
DISPLAY INVISIBLE (-2825 2150);
FORCEPROP 1 LAST PATH I27
J 2
(-2498 2275);
DISPLAY 0.872340 (-2498 2275);
PAINT GREEN (-2498 2275);
DISPLAY INVISIBLE (-2498 2275);
FORCEADD TAP..1
(-850 1175);
FORCEPROP 3 LASTPIN (-900 1175) SIG_NAME M_E_CPU1_SB_DQ<0>
J 0
(-890 1185);
DISPLAY 0.659574 (-890 1185);
PAINT MONO (-890 1185);
DISPLAY INVISIBLE (-890 1185);
FORCEPROP 1 LASTPIN (-900 1175) BN 0
J 0
(-912 1183);
DISPLAY 0.680851 (-912 1183);
PAINT GREEN (-912 1183);
FORCEPROP 2 LAST CDS_LIB standard
J 0
(-850 1175);
PAINT MONO (-850 1175);
DISPLAY INVISIBLE (-850 1175);
FORCEPROP 1 LAST BODY_TYPE PLUMBING
J 0
(-850 1225);
DISPLAY 0.872340 (-850 1225);
PAINT GREEN (-850 1225);
DISPLAY INVISIBLE (-850 1225);
FORCEPROP 1 LAST HDL_TAP TRUE
J 0
(-525 1050);
DISPLAY 0.872340 (-525 1050);
DISPLAY INVISIBLE (-525 1050);
FORCEPROP 1 LAST PATH I28
J 0
(-852 1175);
DISPLAY 0.872340 (-852 1175);
PAINT GREEN (-852 1175);
DISPLAY INVISIBLE (-852 1175);
FORCEADD TAP..1
(-850 1225);
FORCEPROP 3 LASTPIN (-900 1225) SIG_NAME M_E_CPU1_SB_DQ<1>
J 0
(-890 1235);
DISPLAY 0.659574 (-890 1235);
PAINT MONO (-890 1235);
DISPLAY INVISIBLE (-890 1235);
FORCEPROP 1 LASTPIN (-900 1225) BN 1
J 0
(-912 1233);
DISPLAY 0.680851 (-912 1233);
PAINT GREEN (-912 1233);
FORCEPROP 2 LAST CDS_LIB standard
J 0
(-850 1225);
PAINT MONO (-850 1225);
DISPLAY INVISIBLE (-850 1225);
FORCEPROP 1 LAST BODY_TYPE PLUMBING
J 0
(-850 1275);
DISPLAY 0.872340 (-850 1275);
PAINT GREEN (-850 1275);
DISPLAY INVISIBLE (-850 1275);
FORCEPROP 1 LAST HDL_TAP TRUE
J 0
(-525 1100);
DISPLAY 0.872340 (-525 1100);
DISPLAY INVISIBLE (-525 1100);
FORCEPROP 1 LAST PATH I29
J 0
(-852 1225);
DISPLAY 0.872340 (-852 1225);
PAINT GREEN (-852 1225);
DISPLAY INVISIBLE (-852 1225);
FORCEADD OFFPAGE..2
R 2
(-3425 425);
FORCEPROP 2 LAST $XR0 107 
J 0
(-3680 425);
DISPLAY 0.638298 (-3680 425);
PAINT MONO (-3680 425);
FORCEPROP 2 LAST CDS_LIB standard
J 0
(-3425 425);
PAINT MONO (-3425 425);
DISPLAY INVISIBLE (-3425 425);
FORCEPROP 1 LAST OFFPAGE TRUE
J 2
(-3750 300);
DISPLAY 0.872340 (-3750 300);
DISPLAY INVISIBLE (-3750 300);
FORCEPROP 1 LAST COMMENT_BODY TRUE
J 2
(-3380 330);
DISPLAY 0.872340 (-3380 330);
PAINT GREEN (-3380 330);
DISPLAY INVISIBLE (-3380 330);
FORCEPROP 2 LAST PATH I3
J 0
(-3375 500);
DISPLAY 1.021277 (-3375 500);
DISPLAY INVISIBLE (-3375 500);
FORCEADD TAP..1
(-850 1375);
FORCEPROP 3 LASTPIN (-900 1375) SIG_NAME M_E_CPU1_SB_DQ<4>
J 0
(-890 1385);
DISPLAY 0.659574 (-890 1385);
PAINT MONO (-890 1385);
DISPLAY INVISIBLE (-890 1385);
FORCEPROP 1 LASTPIN (-900 1375) BN 4
J 0
(-912 1383);
DISPLAY 0.680851 (-912 1383);
PAINT GREEN (-912 1383);
FORCEPROP 2 LAST CDS_LIB standard
J 0
(-850 1375);
PAINT MONO (-850 1375);
DISPLAY INVISIBLE (-850 1375);
FORCEPROP 1 LAST BODY_TYPE PLUMBING
J 0
(-850 1425);
DISPLAY 0.872340 (-850 1425);
PAINT GREEN (-850 1425);
DISPLAY INVISIBLE (-850 1425);
FORCEPROP 1 LAST HDL_TAP TRUE
J 0
(-525 1250);
DISPLAY 0.872340 (-525 1250);
DISPLAY INVISIBLE (-525 1250);
FORCEPROP 1 LAST PATH I30
J 0
(-852 1375);
DISPLAY 0.872340 (-852 1375);
PAINT GREEN (-852 1375);
DISPLAY INVISIBLE (-852 1375);
FORCEADD TAP..1
(-850 1275);
FORCEPROP 3 LASTPIN (-900 1275) SIG_NAME M_E_CPU1_SB_DQ<2>
J 0
(-890 1285);
DISPLAY 0.659574 (-890 1285);
PAINT MONO (-890 1285);
DISPLAY INVISIBLE (-890 1285);
FORCEPROP 1 LASTPIN (-900 1275) BN 2
J 0
(-912 1283);
DISPLAY 0.680851 (-912 1283);
PAINT GREEN (-912 1283);
FORCEPROP 2 LAST CDS_LIB standard
J 0
(-850 1275);
PAINT MONO (-850 1275);
DISPLAY INVISIBLE (-850 1275);
FORCEPROP 1 LAST BODY_TYPE PLUMBING
J 0
(-850 1325);
DISPLAY 0.872340 (-850 1325);
PAINT GREEN (-850 1325);
DISPLAY INVISIBLE (-850 1325);
FORCEPROP 1 LAST HDL_TAP TRUE
J 0
(-525 1150);
DISPLAY 0.872340 (-525 1150);
DISPLAY INVISIBLE (-525 1150);
FORCEPROP 1 LAST PATH I31
J 0
(-852 1275);
DISPLAY 0.872340 (-852 1275);
PAINT GREEN (-852 1275);
DISPLAY INVISIBLE (-852 1275);
FORCEADD TAP..1
(-850 1325);
FORCEPROP 3 LASTPIN (-900 1325) SIG_NAME M_E_CPU1_SB_DQ<3>
J 0
(-890 1335);
DISPLAY 0.659574 (-890 1335);
PAINT MONO (-890 1335);
DISPLAY INVISIBLE (-890 1335);
FORCEPROP 1 LASTPIN (-900 1325) BN 3
J 0
(-912 1333);
DISPLAY 0.680851 (-912 1333);
PAINT GREEN (-912 1333);
FORCEPROP 2 LAST CDS_LIB standard
J 0
(-850 1325);
PAINT MONO (-850 1325);
DISPLAY INVISIBLE (-850 1325);
FORCEPROP 1 LAST BODY_TYPE PLUMBING
J 0
(-850 1375);
DISPLAY 0.872340 (-850 1375);
PAINT GREEN (-850 1375);
DISPLAY INVISIBLE (-850 1375);
FORCEPROP 1 LAST HDL_TAP TRUE
J 0
(-525 1200);
DISPLAY 0.872340 (-525 1200);
DISPLAY INVISIBLE (-525 1200);
FORCEPROP 1 LAST PATH I32
J 0
(-852 1325);
DISPLAY 0.872340 (-852 1325);
PAINT GREEN (-852 1325);
DISPLAY INVISIBLE (-852 1325);
FORCEADD TAP..1
(-850 1525);
FORCEPROP 3 LASTPIN (-900 1525) SIG_NAME M_E_CPU1_SB_DQ<7>
J 0
(-890 1535);
DISPLAY 0.659574 (-890 1535);
PAINT MONO (-890 1535);
DISPLAY INVISIBLE (-890 1535);
FORCEPROP 1 LASTPIN (-900 1525) BN 7
J 0
(-912 1533);
DISPLAY 0.680851 (-912 1533);
PAINT GREEN (-912 1533);
FORCEPROP 2 LAST CDS_LIB standard
J 0
(-850 1525);
PAINT MONO (-850 1525);
DISPLAY INVISIBLE (-850 1525);
FORCEPROP 1 LAST BODY_TYPE PLUMBING
J 0
(-850 1575);
DISPLAY 0.872340 (-850 1575);
PAINT GREEN (-850 1575);
DISPLAY INVISIBLE (-850 1575);
FORCEPROP 1 LAST HDL_TAP TRUE
J 0
(-525 1400);
DISPLAY 0.872340 (-525 1400);
DISPLAY INVISIBLE (-525 1400);
FORCEPROP 1 LAST PATH I33
J 0
(-852 1525);
DISPLAY 0.872340 (-852 1525);
PAINT GREEN (-852 1525);
DISPLAY INVISIBLE (-852 1525);
FORCEADD TAP..1
(-850 1475);
FORCEPROP 3 LASTPIN (-900 1475) SIG_NAME M_E_CPU1_SB_DQ<6>
J 0
(-890 1485);
DISPLAY 0.659574 (-890 1485);
PAINT MONO (-890 1485);
DISPLAY INVISIBLE (-890 1485);
FORCEPROP 1 LASTPIN (-900 1475) BN 6
J 0
(-912 1483);
DISPLAY 0.680851 (-912 1483);
PAINT GREEN (-912 1483);
FORCEPROP 2 LAST CDS_LIB standard
J 0
(-850 1475);
PAINT MONO (-850 1475);
DISPLAY INVISIBLE (-850 1475);
FORCEPROP 1 LAST BODY_TYPE PLUMBING
J 0
(-850 1525);
DISPLAY 0.872340 (-850 1525);
PAINT GREEN (-850 1525);
DISPLAY INVISIBLE (-850 1525);
FORCEPROP 1 LAST HDL_TAP TRUE
J 0
(-525 1350);
DISPLAY 0.872340 (-525 1350);
DISPLAY INVISIBLE (-525 1350);
FORCEPROP 1 LAST PATH I34
J 0
(-852 1475);
DISPLAY 0.872340 (-852 1475);
PAINT GREEN (-852 1475);
DISPLAY INVISIBLE (-852 1475);
FORCEADD TAP..1
(-850 1425);
FORCEPROP 3 LASTPIN (-900 1425) SIG_NAME M_E_CPU1_SB_DQ<5>
J 0
(-890 1435);
DISPLAY 0.659574 (-890 1435);
PAINT MONO (-890 1435);
DISPLAY INVISIBLE (-890 1435);
FORCEPROP 1 LASTPIN (-900 1425) BN 5
J 0
(-912 1433);
DISPLAY 0.680851 (-912 1433);
PAINT GREEN (-912 1433);
FORCEPROP 2 LAST CDS_LIB standard
J 0
(-850 1425);
PAINT MONO (-850 1425);
DISPLAY INVISIBLE (-850 1425);
FORCEPROP 1 LAST BODY_TYPE PLUMBING
J 0
(-850 1475);
DISPLAY 0.872340 (-850 1475);
PAINT GREEN (-850 1475);
DISPLAY INVISIBLE (-850 1475);
FORCEPROP 1 LAST HDL_TAP TRUE
J 0
(-525 1300);
DISPLAY 0.872340 (-525 1300);
DISPLAY INVISIBLE (-525 1300);
FORCEPROP 1 LAST PATH I35
J 0
(-852 1425);
DISPLAY 0.872340 (-852 1425);
PAINT GREEN (-852 1425);
DISPLAY INVISIBLE (-852 1425);
FORCEADD TAP..1
(-850 1775);
FORCEPROP 3 LASTPIN (-900 1775) SIG_NAME M_E_CPU1_SB_DQ<12>
J 0
(-890 1785);
DISPLAY 0.659574 (-890 1785);
PAINT MONO (-890 1785);
DISPLAY INVISIBLE (-890 1785);
FORCEPROP 1 LASTPIN (-900 1775) BN 12
J 0
(-912 1783);
DISPLAY 0.680851 (-912 1783);
PAINT GREEN (-912 1783);
FORCEPROP 2 LAST CDS_LIB standard
J 0
(-850 1775);
PAINT MONO (-850 1775);
DISPLAY INVISIBLE (-850 1775);
FORCEPROP 1 LAST BODY_TYPE PLUMBING
J 0
(-850 1825);
DISPLAY 0.872340 (-850 1825);
PAINT GREEN (-850 1825);
DISPLAY INVISIBLE (-850 1825);
FORCEPROP 1 LAST HDL_TAP TRUE
J 0
(-525 1650);
DISPLAY 0.872340 (-525 1650);
DISPLAY INVISIBLE (-525 1650);
FORCEPROP 1 LAST PATH I36
J 0
(-852 1775);
DISPLAY 0.872340 (-852 1775);
PAINT GREEN (-852 1775);
DISPLAY INVISIBLE (-852 1775);
FORCEADD TAP..1
(-850 1725);
FORCEPROP 3 LASTPIN (-900 1725) SIG_NAME M_E_CPU1_SB_DQ<11>
J 0
(-890 1735);
DISPLAY 0.659574 (-890 1735);
PAINT MONO (-890 1735);
DISPLAY INVISIBLE (-890 1735);
FORCEPROP 1 LASTPIN (-900 1725) BN 11
J 0
(-912 1733);
DISPLAY 0.680851 (-912 1733);
PAINT GREEN (-912 1733);
FORCEPROP 2 LAST CDS_LIB standard
J 0
(-850 1725);
PAINT MONO (-850 1725);
DISPLAY INVISIBLE (-850 1725);
FORCEPROP 1 LAST BODY_TYPE PLUMBING
J 0
(-850 1775);
DISPLAY 0.872340 (-850 1775);
PAINT GREEN (-850 1775);
DISPLAY INVISIBLE (-850 1775);
FORCEPROP 1 LAST HDL_TAP TRUE
J 0
(-525 1600);
DISPLAY 0.872340 (-525 1600);
DISPLAY INVISIBLE (-525 1600);
FORCEPROP 1 LAST PATH I37
J 0
(-852 1725);
DISPLAY 0.872340 (-852 1725);
PAINT GREEN (-852 1725);
DISPLAY INVISIBLE (-852 1725);
FORCEADD TAP..1
(-850 1675);
FORCEPROP 3 LASTPIN (-900 1675) SIG_NAME M_E_CPU1_SB_DQ<10>
J 0
(-890 1685);
DISPLAY 0.659574 (-890 1685);
PAINT MONO (-890 1685);
DISPLAY INVISIBLE (-890 1685);
FORCEPROP 1 LASTPIN (-900 1675) BN 10
J 0
(-912 1683);
DISPLAY 0.680851 (-912 1683);
PAINT GREEN (-912 1683);
FORCEPROP 2 LAST CDS_LIB standard
J 0
(-850 1675);
PAINT MONO (-850 1675);
DISPLAY INVISIBLE (-850 1675);
FORCEPROP 1 LAST BODY_TYPE PLUMBING
J 0
(-850 1725);
DISPLAY 0.872340 (-850 1725);
PAINT GREEN (-850 1725);
DISPLAY INVISIBLE (-850 1725);
FORCEPROP 1 LAST HDL_TAP TRUE
J 0
(-525 1550);
DISPLAY 0.872340 (-525 1550);
DISPLAY INVISIBLE (-525 1550);
FORCEPROP 1 LAST PATH I38
J 0
(-852 1675);
DISPLAY 0.872340 (-852 1675);
PAINT GREEN (-852 1675);
DISPLAY INVISIBLE (-852 1675);
FORCEADD TAP..1
(-850 1625);
FORCEPROP 3 LASTPIN (-900 1625) SIG_NAME M_E_CPU1_SB_DQ<9>
J 0
(-890 1635);
DISPLAY 0.659574 (-890 1635);
PAINT MONO (-890 1635);
DISPLAY INVISIBLE (-890 1635);
FORCEPROP 1 LASTPIN (-900 1625) BN 9
J 0
(-912 1633);
DISPLAY 0.680851 (-912 1633);
PAINT GREEN (-912 1633);
FORCEPROP 2 LAST CDS_LIB standard
J 0
(-850 1625);
PAINT MONO (-850 1625);
DISPLAY INVISIBLE (-850 1625);
FORCEPROP 1 LAST BODY_TYPE PLUMBING
J 0
(-850 1675);
DISPLAY 0.872340 (-850 1675);
PAINT GREEN (-850 1675);
DISPLAY INVISIBLE (-850 1675);
FORCEPROP 1 LAST HDL_TAP TRUE
J 0
(-525 1500);
DISPLAY 0.872340 (-525 1500);
DISPLAY INVISIBLE (-525 1500);
FORCEPROP 1 LAST PATH I39
J 0
(-852 1625);
DISPLAY 0.872340 (-852 1625);
PAINT GREEN (-852 1625);
DISPLAY INVISIBLE (-852 1625);
FORCEADD OFFPAGE..2
R 2
(-3425 925);
FORCEPROP 2 LAST $XR0 55 
J 0
(-3649 925);
DISPLAY 0.638298 (-3649 925);
PAINT MONO (-3649 925);
FORCEPROP 2 LAST CDS_LIB standard
J 0
(-3425 925);
PAINT MONO (-3425 925);
DISPLAY INVISIBLE (-3425 925);
FORCEPROP 1 LAST OFFPAGE TRUE
J 2
(-3750 800);
DISPLAY 0.872340 (-3750 800);
DISPLAY INVISIBLE (-3750 800);
FORCEPROP 1 LAST COMMENT_BODY TRUE
J 2
(-3380 830);
DISPLAY 0.872340 (-3380 830);
PAINT GREEN (-3380 830);
DISPLAY INVISIBLE (-3380 830);
FORCEPROP 2 LAST PATH I4
J 0
(-3375 1000);
DISPLAY 1.021277 (-3375 1000);
DISPLAY INVISIBLE (-3375 1000);
FORCEADD TAP..1
(-850 1575);
FORCEPROP 3 LASTPIN (-900 1575) SIG_NAME M_E_CPU1_SB_DQ<8>
J 0
(-890 1585);
DISPLAY 0.659574 (-890 1585);
PAINT MONO (-890 1585);
DISPLAY INVISIBLE (-890 1585);
FORCEPROP 1 LASTPIN (-900 1575) BN 8
J 0
(-912 1583);
DISPLAY 0.680851 (-912 1583);
PAINT GREEN (-912 1583);
FORCEPROP 2 LAST CDS_LIB standard
J 0
(-850 1575);
PAINT MONO (-850 1575);
DISPLAY INVISIBLE (-850 1575);
FORCEPROP 1 LAST BODY_TYPE PLUMBING
J 0
(-850 1625);
DISPLAY 0.872340 (-850 1625);
PAINT GREEN (-850 1625);
DISPLAY INVISIBLE (-850 1625);
FORCEPROP 1 LAST HDL_TAP TRUE
J 0
(-525 1450);
DISPLAY 0.872340 (-525 1450);
DISPLAY INVISIBLE (-525 1450);
FORCEPROP 1 LAST PATH I40
J 0
(-852 1575);
DISPLAY 0.872340 (-852 1575);
PAINT GREEN (-852 1575);
DISPLAY INVISIBLE (-852 1575);
FORCEADD TAP..1
(-850 1825);
FORCEPROP 3 LASTPIN (-900 1825) SIG_NAME M_E_CPU1_SB_DQ<13>
J 0
(-890 1835);
DISPLAY 0.659574 (-890 1835);
PAINT MONO (-890 1835);
DISPLAY INVISIBLE (-890 1835);
FORCEPROP 1 LASTPIN (-900 1825) BN 13
J 0
(-912 1833);
DISPLAY 0.680851 (-912 1833);
PAINT GREEN (-912 1833);
FORCEPROP 2 LAST CDS_LIB standard
J 0
(-850 1825);
PAINT MONO (-850 1825);
DISPLAY INVISIBLE (-850 1825);
FORCEPROP 1 LAST BODY_TYPE PLUMBING
J 0
(-850 1875);
DISPLAY 0.872340 (-850 1875);
PAINT GREEN (-850 1875);
DISPLAY INVISIBLE (-850 1875);
FORCEPROP 1 LAST HDL_TAP TRUE
J 0
(-525 1700);
DISPLAY 0.872340 (-525 1700);
DISPLAY INVISIBLE (-525 1700);
FORCEPROP 1 LAST PATH I41
J 0
(-852 1825);
DISPLAY 0.872340 (-852 1825);
PAINT GREEN (-852 1825);
DISPLAY INVISIBLE (-852 1825);
FORCEADD TAP..1
(-850 1875);
FORCEPROP 3 LASTPIN (-900 1875) SIG_NAME M_E_CPU1_SB_DQ<14>
J 0
(-890 1885);
DISPLAY 0.659574 (-890 1885);
PAINT MONO (-890 1885);
DISPLAY INVISIBLE (-890 1885);
FORCEPROP 1 LASTPIN (-900 1875) BN 14
J 0
(-912 1883);
DISPLAY 0.680851 (-912 1883);
PAINT GREEN (-912 1883);
FORCEPROP 2 LAST CDS_LIB standard
J 0
(-850 1875);
PAINT MONO (-850 1875);
DISPLAY INVISIBLE (-850 1875);
FORCEPROP 1 LAST BODY_TYPE PLUMBING
J 0
(-850 1925);
DISPLAY 0.872340 (-850 1925);
PAINT GREEN (-850 1925);
DISPLAY INVISIBLE (-850 1925);
FORCEPROP 1 LAST HDL_TAP TRUE
J 0
(-525 1750);
DISPLAY 0.872340 (-525 1750);
DISPLAY INVISIBLE (-525 1750);
FORCEPROP 1 LAST PATH I42
J 0
(-852 1875);
DISPLAY 0.872340 (-852 1875);
PAINT GREEN (-852 1875);
DISPLAY INVISIBLE (-852 1875);
FORCEADD TAP..1
(-850 1925);
FORCEPROP 3 LASTPIN (-900 1925) SIG_NAME M_E_CPU1_SB_DQ<15>
J 0
(-890 1935);
DISPLAY 0.659574 (-890 1935);
PAINT MONO (-890 1935);
DISPLAY INVISIBLE (-890 1935);
FORCEPROP 1 LASTPIN (-900 1925) BN 15
J 0
(-912 1933);
DISPLAY 0.680851 (-912 1933);
PAINT GREEN (-912 1933);
FORCEPROP 2 LAST CDS_LIB standard
J 0
(-850 1925);
PAINT MONO (-850 1925);
DISPLAY INVISIBLE (-850 1925);
FORCEPROP 1 LAST BODY_TYPE PLUMBING
J 0
(-850 1975);
DISPLAY 0.872340 (-850 1975);
PAINT GREEN (-850 1975);
DISPLAY INVISIBLE (-850 1975);
FORCEPROP 1 LAST HDL_TAP TRUE
J 0
(-525 1800);
DISPLAY 0.872340 (-525 1800);
DISPLAY INVISIBLE (-525 1800);
FORCEPROP 1 LAST PATH I43
J 0
(-852 1925);
DISPLAY 0.872340 (-852 1925);
PAINT GREEN (-852 1925);
DISPLAY INVISIBLE (-852 1925);
FORCEADD TAP..1
(-850 1975);
FORCEPROP 3 LASTPIN (-900 1975) SIG_NAME M_E_CPU1_SB_DQ<16>
J 0
(-890 1985);
DISPLAY 0.659574 (-890 1985);
PAINT MONO (-890 1985);
DISPLAY INVISIBLE (-890 1985);
FORCEPROP 1 LASTPIN (-900 1975) BN 16
J 0
(-912 1983);
DISPLAY 0.680851 (-912 1983);
PAINT GREEN (-912 1983);
FORCEPROP 2 LAST CDS_LIB standard
J 0
(-850 1975);
PAINT MONO (-850 1975);
DISPLAY INVISIBLE (-850 1975);
FORCEPROP 1 LAST BODY_TYPE PLUMBING
J 0
(-850 2025);
DISPLAY 0.872340 (-850 2025);
PAINT GREEN (-850 2025);
DISPLAY INVISIBLE (-850 2025);
FORCEPROP 1 LAST HDL_TAP TRUE
J 0
(-525 1850);
DISPLAY 0.872340 (-525 1850);
DISPLAY INVISIBLE (-525 1850);
FORCEPROP 1 LAST PATH I44
J 0
(-852 1975);
DISPLAY 0.872340 (-852 1975);
PAINT GREEN (-852 1975);
DISPLAY INVISIBLE (-852 1975);
FORCEADD TAP..1
(-850 2025);
FORCEPROP 3 LASTPIN (-900 2025) SIG_NAME M_E_CPU1_SB_DQ<17>
J 0
(-890 2035);
DISPLAY 0.659574 (-890 2035);
PAINT MONO (-890 2035);
DISPLAY INVISIBLE (-890 2035);
FORCEPROP 1 LASTPIN (-900 2025) BN 17
J 0
(-912 2033);
DISPLAY 0.680851 (-912 2033);
PAINT GREEN (-912 2033);
FORCEPROP 2 LAST CDS_LIB standard
J 0
(-850 2025);
PAINT MONO (-850 2025);
DISPLAY INVISIBLE (-850 2025);
FORCEPROP 1 LAST BODY_TYPE PLUMBING
J 0
(-850 2075);
DISPLAY 0.872340 (-850 2075);
PAINT GREEN (-850 2075);
DISPLAY INVISIBLE (-850 2075);
FORCEPROP 1 LAST HDL_TAP TRUE
J 0
(-525 1900);
DISPLAY 0.872340 (-525 1900);
DISPLAY INVISIBLE (-525 1900);
FORCEPROP 1 LAST PATH I45
J 0
(-852 2025);
DISPLAY 0.872340 (-852 2025);
PAINT GREEN (-852 2025);
DISPLAY INVISIBLE (-852 2025);
FORCEADD TAP..1
(-850 2275);
FORCEPROP 3 LASTPIN (-900 2275) SIG_NAME M_E_CPU1_SB_DQ<22>
J 0
(-890 2285);
DISPLAY 0.659574 (-890 2285);
PAINT MONO (-890 2285);
DISPLAY INVISIBLE (-890 2285);
FORCEPROP 1 LASTPIN (-900 2275) BN 22
J 0
(-912 2283);
DISPLAY 0.680851 (-912 2283);
PAINT GREEN (-912 2283);
FORCEPROP 2 LAST CDS_LIB standard
J 0
(-850 2275);
DISPLAY INVISIBLE (-850 2275);
FORCEPROP 1 LAST BODY_TYPE PLUMBING
J 0
(-850 2325);
DISPLAY 0.872340 (-850 2325);
PAINT GREEN (-850 2325);
DISPLAY INVISIBLE (-850 2325);
FORCEPROP 1 LAST HDL_TAP TRUE
J 0
(-525 2150);
DISPLAY 0.872340 (-525 2150);
DISPLAY INVISIBLE (-525 2150);
FORCEPROP 1 LAST PATH I46
J 0
(-852 2275);
DISPLAY 0.872340 (-852 2275);
PAINT GREEN (-852 2275);
DISPLAY INVISIBLE (-852 2275);
FORCEADD TAP..1
(-850 2225);
FORCEPROP 3 LASTPIN (-900 2225) SIG_NAME M_E_CPU1_SB_DQ<21>
J 0
(-890 2235);
DISPLAY 0.659574 (-890 2235);
PAINT MONO (-890 2235);
DISPLAY INVISIBLE (-890 2235);
FORCEPROP 1 LASTPIN (-900 2225) BN 21
J 0
(-912 2233);
DISPLAY 0.680851 (-912 2233);
PAINT GREEN (-912 2233);
FORCEPROP 2 LAST CDS_LIB standard
J 0
(-850 2225);
PAINT MONO (-850 2225);
DISPLAY INVISIBLE (-850 2225);
FORCEPROP 1 LAST BODY_TYPE PLUMBING
J 0
(-850 2275);
DISPLAY 0.872340 (-850 2275);
PAINT GREEN (-850 2275);
DISPLAY INVISIBLE (-850 2275);
FORCEPROP 1 LAST HDL_TAP TRUE
J 0
(-525 2100);
DISPLAY 0.872340 (-525 2100);
DISPLAY INVISIBLE (-525 2100);
FORCEPROP 1 LAST PATH I47
J 0
(-852 2225);
DISPLAY 0.872340 (-852 2225);
PAINT GREEN (-852 2225);
DISPLAY INVISIBLE (-852 2225);
FORCEADD TAP..1
(-850 2175);
FORCEPROP 3 LASTPIN (-900 2175) SIG_NAME M_E_CPU1_SB_DQ<20>
J 0
(-890 2185);
DISPLAY 0.659574 (-890 2185);
PAINT MONO (-890 2185);
DISPLAY INVISIBLE (-890 2185);
FORCEPROP 1 LASTPIN (-900 2175) BN 20
J 0
(-912 2183);
DISPLAY 0.680851 (-912 2183);
PAINT GREEN (-912 2183);
FORCEPROP 2 LAST CDS_LIB standard
J 0
(-850 2175);
PAINT MONO (-850 2175);
DISPLAY INVISIBLE (-850 2175);
FORCEPROP 1 LAST BODY_TYPE PLUMBING
J 0
(-850 2225);
DISPLAY 0.872340 (-850 2225);
PAINT GREEN (-850 2225);
DISPLAY INVISIBLE (-850 2225);
FORCEPROP 1 LAST HDL_TAP TRUE
J 0
(-525 2050);
DISPLAY 0.872340 (-525 2050);
DISPLAY INVISIBLE (-525 2050);
FORCEPROP 1 LAST PATH I48
J 0
(-852 2175);
DISPLAY 0.872340 (-852 2175);
PAINT GREEN (-852 2175);
DISPLAY INVISIBLE (-852 2175);
FORCEADD TAP..1
(-850 2125);
FORCEPROP 3 LASTPIN (-900 2125) SIG_NAME M_E_CPU1_SB_DQ<19>
J 0
(-890 2135);
DISPLAY 0.659574 (-890 2135);
PAINT MONO (-890 2135);
DISPLAY INVISIBLE (-890 2135);
FORCEPROP 1 LASTPIN (-900 2125) BN 19
J 0
(-912 2133);
DISPLAY 0.680851 (-912 2133);
PAINT GREEN (-912 2133);
FORCEPROP 2 LAST CDS_LIB standard
J 0
(-850 2125);
PAINT MONO (-850 2125);
DISPLAY INVISIBLE (-850 2125);
FORCEPROP 1 LAST BODY_TYPE PLUMBING
J 0
(-850 2175);
DISPLAY 0.872340 (-850 2175);
PAINT GREEN (-850 2175);
DISPLAY INVISIBLE (-850 2175);
FORCEPROP 1 LAST HDL_TAP TRUE
J 0
(-525 2000);
DISPLAY 0.872340 (-525 2000);
DISPLAY INVISIBLE (-525 2000);
FORCEPROP 1 LAST PATH I49
J 0
(-852 2125);
DISPLAY 0.872340 (-852 2125);
PAINT GREEN (-852 2125);
DISPLAY INVISIBLE (-852 2125);
FORCEADD OFFPAGE..2
R 2
(-3425 975);
FORCEPROP 2 LAST $XR0 55 
J 0
(-3649 975);
DISPLAY 0.638298 (-3649 975);
PAINT MONO (-3649 975);
FORCEPROP 2 LAST CDS_LIB standard
J 0
(-3425 975);
PAINT MONO (-3425 975);
DISPLAY INVISIBLE (-3425 975);
FORCEPROP 1 LAST OFFPAGE TRUE
J 2
(-3750 850);
DISPLAY 0.872340 (-3750 850);
DISPLAY INVISIBLE (-3750 850);
FORCEPROP 1 LAST COMMENT_BODY TRUE
J 2
(-3380 880);
DISPLAY 0.872340 (-3380 880);
PAINT GREEN (-3380 880);
DISPLAY INVISIBLE (-3380 880);
FORCEPROP 2 LAST PATH I5
J 0
(-3375 1050);
DISPLAY 1.021277 (-3375 1050);
DISPLAY INVISIBLE (-3375 1050);
FORCEADD TAP..1
(-850 2075);
FORCEPROP 3 LASTPIN (-900 2075) SIG_NAME M_E_CPU1_SB_DQ<18>
J 0
(-890 2085);
DISPLAY 0.659574 (-890 2085);
PAINT MONO (-890 2085);
DISPLAY INVISIBLE (-890 2085);
FORCEPROP 1 LASTPIN (-900 2075) BN 18
J 0
(-912 2083);
DISPLAY 0.680851 (-912 2083);
PAINT GREEN (-912 2083);
FORCEPROP 2 LAST CDS_LIB standard
J 0
(-850 2075);
PAINT MONO (-850 2075);
DISPLAY INVISIBLE (-850 2075);
FORCEPROP 1 LAST BODY_TYPE PLUMBING
J 0
(-850 2125);
DISPLAY 0.872340 (-850 2125);
PAINT GREEN (-850 2125);
DISPLAY INVISIBLE (-850 2125);
FORCEPROP 1 LAST HDL_TAP TRUE
J 0
(-525 1950);
DISPLAY 0.872340 (-525 1950);
DISPLAY INVISIBLE (-525 1950);
FORCEPROP 1 LAST PATH I50
J 0
(-852 2075);
DISPLAY 0.872340 (-852 2075);
PAINT GREEN (-852 2075);
DISPLAY INVISIBLE (-852 2075);
FORCEADD TAP..1
R 2
(-2500 2325);
FORCEPROP 3 LASTPIN (-2450 2325) SIG_NAME M_E_CPU1_SB_CB<3>
J 0
(-2440 2335);
DISPLAY 0.659574 (-2440 2335);
PAINT MONO (-2440 2335);
DISPLAY INVISIBLE (-2440 2335);
FORCEPROP 1 LASTPIN (-2450 2325) BN 3
J 2
(-2438 2333);
DISPLAY 0.680851 (-2438 2333);
PAINT GREEN (-2438 2333);
FORCEPROP 2 LAST CDS_LIB standard
J 0
(-2500 2325);
DISPLAY INVISIBLE (-2500 2325);
FORCEPROP 1 LAST BODY_TYPE PLUMBING
J 2
(-2500 2375);
DISPLAY 0.872340 (-2500 2375);
PAINT GREEN (-2500 2375);
DISPLAY INVISIBLE (-2500 2375);
FORCEPROP 1 LAST HDL_TAP TRUE
J 2
(-2825 2200);
DISPLAY 0.872340 (-2825 2200);
DISPLAY INVISIBLE (-2825 2200);
FORCEPROP 1 LAST PATH I51
J 2
(-2498 2325);
DISPLAY 0.872340 (-2498 2325);
PAINT GREEN (-2498 2325);
DISPLAY INVISIBLE (-2498 2325);
FORCEADD TAP..1
R 2
(-2500 2375);
FORCEPROP 3 LASTPIN (-2450 2375) SIG_NAME M_E_CPU1_SB_CB<4>
J 0
(-2440 2385);
DISPLAY 0.659574 (-2440 2385);
PAINT MONO (-2440 2385);
DISPLAY INVISIBLE (-2440 2385);
FORCEPROP 1 LASTPIN (-2450 2375) BN 4
J 2
(-2438 2383);
DISPLAY 0.680851 (-2438 2383);
PAINT GREEN (-2438 2383);
FORCEPROP 2 LAST CDS_LIB standard
J 0
(-2500 2375);
DISPLAY INVISIBLE (-2500 2375);
FORCEPROP 1 LAST BODY_TYPE PLUMBING
J 2
(-2500 2425);
DISPLAY 0.872340 (-2500 2425);
PAINT GREEN (-2500 2425);
DISPLAY INVISIBLE (-2500 2425);
FORCEPROP 1 LAST HDL_TAP TRUE
J 2
(-2825 2250);
DISPLAY 0.872340 (-2825 2250);
DISPLAY INVISIBLE (-2825 2250);
FORCEPROP 1 LAST PATH I52
J 2
(-2498 2375);
DISPLAY 0.872340 (-2498 2375);
PAINT GREEN (-2498 2375);
DISPLAY INVISIBLE (-2498 2375);
FORCEADD TAP..1
R 2
(-2500 2425);
FORCEPROP 3 LASTPIN (-2450 2425) SIG_NAME M_E_CPU1_SB_CB<5>
J 0
(-2440 2435);
DISPLAY 0.659574 (-2440 2435);
PAINT MONO (-2440 2435);
DISPLAY INVISIBLE (-2440 2435);
FORCEPROP 1 LASTPIN (-2450 2425) BN 5
J 2
(-2438 2433);
DISPLAY 0.680851 (-2438 2433);
PAINT GREEN (-2438 2433);
FORCEPROP 2 LAST CDS_LIB standard
J 0
(-2500 2425);
DISPLAY INVISIBLE (-2500 2425);
FORCEPROP 1 LAST BODY_TYPE PLUMBING
J 2
(-2500 2475);
DISPLAY 0.872340 (-2500 2475);
PAINT GREEN (-2500 2475);
DISPLAY INVISIBLE (-2500 2475);
FORCEPROP 1 LAST HDL_TAP TRUE
J 2
(-2825 2300);
DISPLAY 0.872340 (-2825 2300);
DISPLAY INVISIBLE (-2825 2300);
FORCEPROP 1 LAST PATH I53
J 2
(-2498 2425);
DISPLAY 0.872340 (-2498 2425);
PAINT GREEN (-2498 2425);
DISPLAY INVISIBLE (-2498 2425);
FORCEADD TAP..1
R 2
(-2500 2525);
FORCEPROP 3 LASTPIN (-2450 2525) SIG_NAME M_E_CPU1_SB_CB<7>
J 0
(-2440 2535);
DISPLAY 0.659574 (-2440 2535);
PAINT MONO (-2440 2535);
DISPLAY INVISIBLE (-2440 2535);
FORCEPROP 1 LASTPIN (-2450 2525) BN 7
J 2
(-2438 2533);
DISPLAY 0.680851 (-2438 2533);
PAINT GREEN (-2438 2533);
FORCEPROP 2 LAST CDS_LIB standard
J 0
(-2500 2525);
DISPLAY INVISIBLE (-2500 2525);
FORCEPROP 1 LAST BODY_TYPE PLUMBING
J 2
(-2500 2575);
DISPLAY 0.872340 (-2500 2575);
PAINT GREEN (-2500 2575);
DISPLAY INVISIBLE (-2500 2575);
FORCEPROP 1 LAST HDL_TAP TRUE
J 2
(-2825 2400);
DISPLAY 0.872340 (-2825 2400);
DISPLAY INVISIBLE (-2825 2400);
FORCEPROP 1 LAST PATH I54
J 2
(-2498 2525);
DISPLAY 0.872340 (-2498 2525);
PAINT GREEN (-2498 2525);
DISPLAY INVISIBLE (-2498 2525);
FORCEADD TAP..1
R 2
(-2500 2475);
FORCEPROP 3 LASTPIN (-2450 2475) SIG_NAME M_E_CPU1_SB_CB<6>
J 0
(-2440 2485);
DISPLAY 0.659574 (-2440 2485);
PAINT MONO (-2440 2485);
DISPLAY INVISIBLE (-2440 2485);
FORCEPROP 1 LASTPIN (-2450 2475) BN 6
J 2
(-2438 2483);
DISPLAY 0.680851 (-2438 2483);
PAINT GREEN (-2438 2483);
FORCEPROP 2 LAST CDS_LIB standard
J 0
(-2500 2475);
DISPLAY INVISIBLE (-2500 2475);
FORCEPROP 1 LAST BODY_TYPE PLUMBING
J 2
(-2500 2525);
DISPLAY 0.872340 (-2500 2525);
PAINT GREEN (-2500 2525);
DISPLAY INVISIBLE (-2500 2525);
FORCEPROP 1 LAST HDL_TAP TRUE
J 2
(-2825 2350);
DISPLAY 0.872340 (-2825 2350);
DISPLAY INVISIBLE (-2825 2350);
FORCEPROP 1 LAST PATH I55
J 2
(-2498 2475);
DISPLAY 0.872340 (-2498 2475);
PAINT GREEN (-2498 2475);
DISPLAY INVISIBLE (-2498 2475);
FORCEADD TAP..1
R 2
(-2500 2625);
FORCEPROP 3 LASTPIN (-2450 2625) SIG_NAME M_E_CPU1_SA_CB<0>
J 0
(-2440 2635);
DISPLAY 0.659574 (-2440 2635);
PAINT MONO (-2440 2635);
DISPLAY INVISIBLE (-2440 2635);
FORCEPROP 1 LASTPIN (-2450 2625) BN 0
J 2
(-2438 2633);
DISPLAY 0.680851 (-2438 2633);
PAINT GREEN (-2438 2633);
FORCEPROP 2 LAST CDS_LIB standard
J 0
(-2500 2625);
PAINT MONO (-2500 2625);
DISPLAY INVISIBLE (-2500 2625);
FORCEPROP 1 LAST BODY_TYPE PLUMBING
J 2
(-2500 2675);
DISPLAY 0.872340 (-2500 2675);
PAINT GREEN (-2500 2675);
DISPLAY INVISIBLE (-2500 2675);
FORCEPROP 1 LAST HDL_TAP TRUE
J 2
(-2825 2500);
DISPLAY 0.872340 (-2825 2500);
DISPLAY INVISIBLE (-2825 2500);
FORCEPROP 1 LAST PATH I56
J 2
(-2498 2625);
DISPLAY 0.872340 (-2498 2625);
PAINT GREEN (-2498 2625);
DISPLAY INVISIBLE (-2498 2625);
FORCEADD TAP..1
R 2
(-2500 2775);
FORCEPROP 3 LASTPIN (-2450 2775) SIG_NAME M_E_CPU1_SA_CB<3>
J 0
(-2440 2785);
DISPLAY 0.659574 (-2440 2785);
PAINT MONO (-2440 2785);
DISPLAY INVISIBLE (-2440 2785);
FORCEPROP 1 LASTPIN (-2450 2775) BN 3
J 2
(-2438 2783);
DISPLAY 0.680851 (-2438 2783);
PAINT GREEN (-2438 2783);
FORCEPROP 2 LAST CDS_LIB standard
J 0
(-2500 2775);
DISPLAY INVISIBLE (-2500 2775);
FORCEPROP 1 LAST BODY_TYPE PLUMBING
J 2
(-2500 2825);
DISPLAY 0.872340 (-2500 2825);
PAINT GREEN (-2500 2825);
DISPLAY INVISIBLE (-2500 2825);
FORCEPROP 1 LAST HDL_TAP TRUE
J 2
(-2825 2650);
DISPLAY 0.872340 (-2825 2650);
DISPLAY INVISIBLE (-2825 2650);
FORCEPROP 1 LAST PATH I57
J 2
(-2498 2775);
DISPLAY 0.872340 (-2498 2775);
PAINT GREEN (-2498 2775);
DISPLAY INVISIBLE (-2498 2775);
FORCEADD TAP..1
R 2
(-2500 2725);
FORCEPROP 3 LASTPIN (-2450 2725) SIG_NAME M_E_CPU1_SA_CB<2>
J 0
(-2440 2735);
DISPLAY 0.659574 (-2440 2735);
PAINT MONO (-2440 2735);
DISPLAY INVISIBLE (-2440 2735);
FORCEPROP 1 LASTPIN (-2450 2725) BN 2
J 2
(-2438 2733);
DISPLAY 0.680851 (-2438 2733);
PAINT GREEN (-2438 2733);
FORCEPROP 2 LAST CDS_LIB standard
J 0
(-2500 2725);
DISPLAY INVISIBLE (-2500 2725);
FORCEPROP 1 LAST BODY_TYPE PLUMBING
J 2
(-2500 2775);
DISPLAY 0.872340 (-2500 2775);
PAINT GREEN (-2500 2775);
DISPLAY INVISIBLE (-2500 2775);
FORCEPROP 1 LAST HDL_TAP TRUE
J 2
(-2825 2600);
DISPLAY 0.872340 (-2825 2600);
DISPLAY INVISIBLE (-2825 2600);
FORCEPROP 1 LAST PATH I58
J 2
(-2498 2725);
DISPLAY 0.872340 (-2498 2725);
PAINT GREEN (-2498 2725);
DISPLAY INVISIBLE (-2498 2725);
FORCEADD TAP..1
R 2
(-2500 2675);
FORCEPROP 3 LASTPIN (-2450 2675) SIG_NAME M_E_CPU1_SA_CB<1>
J 0
(-2440 2685);
DISPLAY 0.659574 (-2440 2685);
PAINT MONO (-2440 2685);
DISPLAY INVISIBLE (-2440 2685);
FORCEPROP 1 LASTPIN (-2450 2675) BN 1
J 2
(-2438 2683);
DISPLAY 0.680851 (-2438 2683);
PAINT GREEN (-2438 2683);
FORCEPROP 2 LAST CDS_LIB standard
J 0
(-2500 2675);
DISPLAY INVISIBLE (-2500 2675);
FORCEPROP 1 LAST BODY_TYPE PLUMBING
J 2
(-2500 2725);
DISPLAY 0.872340 (-2500 2725);
PAINT GREEN (-2500 2725);
DISPLAY INVISIBLE (-2500 2725);
FORCEPROP 1 LAST HDL_TAP TRUE
J 2
(-2825 2550);
DISPLAY 0.872340 (-2825 2550);
DISPLAY INVISIBLE (-2825 2550);
FORCEPROP 1 LAST PATH I59
J 2
(-2498 2675);
DISPLAY 0.872340 (-2498 2675);
PAINT GREEN (-2498 2675);
DISPLAY INVISIBLE (-2498 2675);
FORCEADD OFFPAGE..3
R 2
(-3425 1525);
FORCEPROP 2 LAST $XR0 114 
J 0
(-3705 1525);
DISPLAY 0.638298 (-3705 1525);
PAINT MONO (-3705 1525);
FORCEPROP 2 LAST CDS_LIB standard
J 0
(-3425 1525);
PAINT MONO (-3425 1525);
DISPLAY INVISIBLE (-3425 1525);
FORCEPROP 1 LAST OFFPAGE TRUE
J 2
(-3750 1400);
DISPLAY 0.872340 (-3750 1400);
DISPLAY INVISIBLE (-3750 1400);
FORCEPROP 1 LAST COMMENT_BODY TRUE
J 2
(-3375 1425);
DISPLAY 0.872340 (-3375 1425);
PAINT GREEN (-3375 1425);
DISPLAY INVISIBLE (-3375 1425);
FORCEPROP 2 LAST PATH I6
J 0
(-3375 1600);
DISPLAY 1.021277 (-3375 1600);
DISPLAY INVISIBLE (-3375 1600);
FORCEADD TAP..1
R 2
(-2500 2875);
FORCEPROP 3 LASTPIN (-2450 2875) SIG_NAME M_E_CPU1_SA_CB<5>
J 0
(-2440 2885);
DISPLAY 0.659574 (-2440 2885);
PAINT MONO (-2440 2885);
DISPLAY INVISIBLE (-2440 2885);
FORCEPROP 1 LASTPIN (-2450 2875) BN 5
J 2
(-2438 2883);
DISPLAY 0.680851 (-2438 2883);
PAINT GREEN (-2438 2883);
FORCEPROP 2 LAST CDS_LIB standard
J 0
(-2500 2875);
DISPLAY INVISIBLE (-2500 2875);
FORCEPROP 1 LAST BODY_TYPE PLUMBING
J 2
(-2500 2925);
DISPLAY 0.872340 (-2500 2925);
PAINT GREEN (-2500 2925);
DISPLAY INVISIBLE (-2500 2925);
FORCEPROP 1 LAST HDL_TAP TRUE
J 2
(-2825 2750);
DISPLAY 0.872340 (-2825 2750);
DISPLAY INVISIBLE (-2825 2750);
FORCEPROP 1 LAST PATH I60
J 2
(-2498 2875);
DISPLAY 0.872340 (-2498 2875);
PAINT GREEN (-2498 2875);
DISPLAY INVISIBLE (-2498 2875);
FORCEADD TAP..1
R 2
(-2500 2975);
FORCEPROP 3 LASTPIN (-2450 2975) SIG_NAME M_E_CPU1_SA_CB<7>
J 0
(-2440 2985);
DISPLAY 0.659574 (-2440 2985);
PAINT MONO (-2440 2985);
DISPLAY INVISIBLE (-2440 2985);
FORCEPROP 1 LASTPIN (-2450 2975) BN 7
J 2
(-2438 2983);
DISPLAY 0.680851 (-2438 2983);
PAINT GREEN (-2438 2983);
FORCEPROP 2 LAST CDS_LIB standard
J 0
(-2500 2975);
DISPLAY INVISIBLE (-2500 2975);
FORCEPROP 1 LAST BODY_TYPE PLUMBING
J 2
(-2500 3025);
DISPLAY 0.872340 (-2500 3025);
PAINT GREEN (-2500 3025);
DISPLAY INVISIBLE (-2500 3025);
FORCEPROP 1 LAST HDL_TAP TRUE
J 2
(-2825 2850);
DISPLAY 0.872340 (-2825 2850);
DISPLAY INVISIBLE (-2825 2850);
FORCEPROP 1 LAST PATH I61
J 2
(-2498 2975);
DISPLAY 0.872340 (-2498 2975);
PAINT GREEN (-2498 2975);
DISPLAY INVISIBLE (-2498 2975);
FORCEADD TAP..1
R 2
(-2500 2925);
FORCEPROP 3 LASTPIN (-2450 2925) SIG_NAME M_E_CPU1_SA_CB<6>
J 0
(-2440 2935);
DISPLAY 0.659574 (-2440 2935);
PAINT MONO (-2440 2935);
DISPLAY INVISIBLE (-2440 2935);
FORCEPROP 1 LASTPIN (-2450 2925) BN 6
J 2
(-2438 2933);
DISPLAY 0.680851 (-2438 2933);
PAINT GREEN (-2438 2933);
FORCEPROP 2 LAST CDS_LIB standard
J 0
(-2500 2925);
DISPLAY INVISIBLE (-2500 2925);
FORCEPROP 1 LAST BODY_TYPE PLUMBING
J 2
(-2500 2975);
DISPLAY 0.872340 (-2500 2975);
PAINT GREEN (-2500 2975);
DISPLAY INVISIBLE (-2500 2975);
FORCEPROP 1 LAST HDL_TAP TRUE
J 2
(-2825 2800);
DISPLAY 0.872340 (-2825 2800);
DISPLAY INVISIBLE (-2825 2800);
FORCEPROP 1 LAST PATH I62
J 2
(-2498 2925);
DISPLAY 0.872340 (-2498 2925);
PAINT GREEN (-2498 2925);
DISPLAY INVISIBLE (-2498 2925);
FORCEADD TAP..1
R 2
(-2500 2825);
FORCEPROP 3 LASTPIN (-2450 2825) SIG_NAME M_E_CPU1_SA_CB<4>
J 0
(-2440 2835);
DISPLAY 0.659574 (-2440 2835);
PAINT MONO (-2440 2835);
DISPLAY INVISIBLE (-2440 2835);
FORCEPROP 1 LASTPIN (-2450 2825) BN 4
J 2
(-2438 2833);
DISPLAY 0.680851 (-2438 2833);
PAINT GREEN (-2438 2833);
FORCEPROP 2 LAST CDS_LIB standard
J 0
(-2500 2825);
DISPLAY INVISIBLE (-2500 2825);
FORCEPROP 1 LAST BODY_TYPE PLUMBING
J 2
(-2500 2875);
DISPLAY 0.872340 (-2500 2875);
PAINT GREEN (-2500 2875);
DISPLAY INVISIBLE (-2500 2875);
FORCEPROP 1 LAST HDL_TAP TRUE
J 2
(-2825 2700);
DISPLAY 0.872340 (-2825 2700);
DISPLAY INVISIBLE (-2825 2700);
FORCEPROP 1 LAST PATH I63
J 2
(-2498 2825);
DISPLAY 0.872340 (-2498 2825);
PAINT GREEN (-2498 2825);
DISPLAY INVISIBLE (-2498 2825);
FORCEADD TAP..1
R 2
(-2500 3775);
FORCEPROP 3 LASTPIN (-2450 3775) SIG_NAME M_E_CPU1_SB_CA<2>
J 0
(-2440 3785);
DISPLAY 0.659574 (-2440 3785);
PAINT MONO (-2440 3785);
DISPLAY INVISIBLE (-2440 3785);
FORCEPROP 1 LASTPIN (-2450 3775) BN 2
J 2
(-2438 3783);
DISPLAY 0.680851 (-2438 3783);
PAINT GREEN (-2438 3783);
FORCEPROP 2 LAST CDS_LIB standard
J 0
(-2500 3775);
DISPLAY INVISIBLE (-2500 3775);
FORCEPROP 1 LAST BODY_TYPE PLUMBING
J 2
(-2500 3825);
DISPLAY 0.872340 (-2500 3825);
PAINT GREEN (-2500 3825);
DISPLAY INVISIBLE (-2500 3825);
FORCEPROP 1 LAST HDL_TAP TRUE
J 2
(-2825 3650);
DISPLAY 0.872340 (-2825 3650);
DISPLAY INVISIBLE (-2825 3650);
FORCEPROP 1 LAST PATH I64
J 2
(-2498 3775);
DISPLAY 0.872340 (-2498 3775);
PAINT GREEN (-2498 3775);
DISPLAY INVISIBLE (-2498 3775);
FORCEADD TAP..1
R 2
(-2500 3725);
FORCEPROP 3 LASTPIN (-2450 3725) SIG_NAME M_E_CPU1_SB_CA<1>
J 0
(-2440 3735);
DISPLAY 0.659574 (-2440 3735);
PAINT MONO (-2440 3735);
DISPLAY INVISIBLE (-2440 3735);
FORCEPROP 1 LASTPIN (-2450 3725) BN 1
J 2
(-2438 3733);
DISPLAY 0.680851 (-2438 3733);
PAINT GREEN (-2438 3733);
FORCEPROP 2 LAST CDS_LIB standard
J 0
(-2500 3725);
DISPLAY INVISIBLE (-2500 3725);
FORCEPROP 1 LAST BODY_TYPE PLUMBING
J 2
(-2500 3775);
DISPLAY 0.872340 (-2500 3775);
PAINT GREEN (-2500 3775);
DISPLAY INVISIBLE (-2500 3775);
FORCEPROP 1 LAST HDL_TAP TRUE
J 2
(-2825 3600);
DISPLAY 0.872340 (-2825 3600);
DISPLAY INVISIBLE (-2825 3600);
FORCEPROP 1 LAST PATH I65
J 2
(-2498 3725);
DISPLAY 0.872340 (-2498 3725);
PAINT GREEN (-2498 3725);
DISPLAY INVISIBLE (-2498 3725);
FORCEADD TAP..1
R 2
(-2500 3675);
FORCEPROP 3 LASTPIN (-2450 3675) SIG_NAME M_E_CPU1_SB_CA<0>
J 0
(-2440 3685);
DISPLAY 0.659574 (-2440 3685);
PAINT MONO (-2440 3685);
DISPLAY INVISIBLE (-2440 3685);
FORCEPROP 1 LASTPIN (-2450 3675) BN 0
J 2
(-2438 3683);
DISPLAY 0.680851 (-2438 3683);
PAINT GREEN (-2438 3683);
FORCEPROP 2 LAST CDS_LIB standard
J 0
(-2500 3675);
DISPLAY INVISIBLE (-2500 3675);
FORCEPROP 1 LAST BODY_TYPE PLUMBING
J 2
(-2500 3725);
DISPLAY 0.872340 (-2500 3725);
PAINT GREEN (-2500 3725);
DISPLAY INVISIBLE (-2500 3725);
FORCEPROP 1 LAST HDL_TAP TRUE
J 2
(-2825 3550);
DISPLAY 0.872340 (-2825 3550);
DISPLAY INVISIBLE (-2825 3550);
FORCEPROP 1 LAST PATH I66
J 2
(-2498 3675);
DISPLAY 0.872340 (-2498 3675);
PAINT GREEN (-2498 3675);
DISPLAY INVISIBLE (-2498 3675);
FORCEADD TAP..1
R 2
(-2500 3825);
FORCEPROP 3 LASTPIN (-2450 3825) SIG_NAME M_E_CPU1_SB_CA<3>
J 0
(-2440 3835);
DISPLAY 0.659574 (-2440 3835);
PAINT MONO (-2440 3835);
DISPLAY INVISIBLE (-2440 3835);
FORCEPROP 1 LASTPIN (-2450 3825) BN 3
J 2
(-2438 3833);
DISPLAY 0.680851 (-2438 3833);
PAINT GREEN (-2438 3833);
FORCEPROP 2 LAST CDS_LIB standard
J 0
(-2500 3825);
DISPLAY INVISIBLE (-2500 3825);
FORCEPROP 1 LAST BODY_TYPE PLUMBING
J 2
(-2500 3875);
DISPLAY 0.872340 (-2500 3875);
PAINT GREEN (-2500 3875);
DISPLAY INVISIBLE (-2500 3875);
FORCEPROP 1 LAST HDL_TAP TRUE
J 2
(-2825 3700);
DISPLAY 0.872340 (-2825 3700);
DISPLAY INVISIBLE (-2825 3700);
FORCEPROP 1 LAST PATH I67
J 2
(-2498 3825);
DISPLAY 0.872340 (-2498 3825);
PAINT GREEN (-2498 3825);
DISPLAY INVISIBLE (-2498 3825);
FORCEADD TAP..1
R 2
(-2500 3975);
FORCEPROP 3 LASTPIN (-2450 3975) SIG_NAME M_E_CPU1_SB_CA<6>
J 0
(-2440 3985);
DISPLAY 0.659574 (-2440 3985);
PAINT MONO (-2440 3985);
DISPLAY INVISIBLE (-2440 3985);
FORCEPROP 1 LASTPIN (-2450 3975) BN 6
J 2
(-2438 3983);
DISPLAY 0.680851 (-2438 3983);
PAINT GREEN (-2438 3983);
FORCEPROP 2 LAST CDS_LIB standard
J 0
(-2500 3975);
DISPLAY INVISIBLE (-2500 3975);
FORCEPROP 1 LAST BODY_TYPE PLUMBING
J 2
(-2500 4025);
DISPLAY 0.872340 (-2500 4025);
PAINT GREEN (-2500 4025);
DISPLAY INVISIBLE (-2500 4025);
FORCEPROP 1 LAST HDL_TAP TRUE
J 2
(-2825 3850);
DISPLAY 0.872340 (-2825 3850);
DISPLAY INVISIBLE (-2825 3850);
FORCEPROP 1 LAST PATH I68
J 2
(-2498 3975);
DISPLAY 0.872340 (-2498 3975);
PAINT GREEN (-2498 3975);
DISPLAY INVISIBLE (-2498 3975);
FORCEADD TAP..1
R 2
(-2500 3925);
FORCEPROP 3 LASTPIN (-2450 3925) SIG_NAME M_E_CPU1_SB_CA<5>
J 0
(-2440 3935);
DISPLAY 0.659574 (-2440 3935);
PAINT MONO (-2440 3935);
DISPLAY INVISIBLE (-2440 3935);
FORCEPROP 1 LASTPIN (-2450 3925) BN 5
J 2
(-2438 3933);
DISPLAY 0.680851 (-2438 3933);
PAINT GREEN (-2438 3933);
FORCEPROP 2 LAST CDS_LIB standard
J 0
(-2500 3925);
DISPLAY INVISIBLE (-2500 3925);
FORCEPROP 1 LAST BODY_TYPE PLUMBING
J 2
(-2500 3975);
DISPLAY 0.872340 (-2500 3975);
PAINT GREEN (-2500 3975);
DISPLAY INVISIBLE (-2500 3975);
FORCEPROP 1 LAST HDL_TAP TRUE
J 2
(-2825 3800);
DISPLAY 0.872340 (-2825 3800);
DISPLAY INVISIBLE (-2825 3800);
FORCEPROP 1 LAST PATH I69
J 2
(-2498 3925);
DISPLAY 0.872340 (-2498 3925);
PAINT GREEN (-2498 3925);
DISPLAY INVISIBLE (-2498 3925);
FORCEADD TAP..1
R 2
(-2500 3875);
FORCEPROP 3 LASTPIN (-2450 3875) SIG_NAME M_E_CPU1_SB_CA<4>
J 0
(-2440 3885);
DISPLAY 0.659574 (-2440 3885);
PAINT MONO (-2440 3885);
DISPLAY INVISIBLE (-2440 3885);
FORCEPROP 1 LASTPIN (-2450 3875) BN 4
J 2
(-2438 3883);
DISPLAY 0.680851 (-2438 3883);
PAINT GREEN (-2438 3883);
FORCEPROP 2 LAST CDS_LIB standard
J 0
(-2500 3875);
DISPLAY INVISIBLE (-2500 3875);
FORCEPROP 1 LAST BODY_TYPE PLUMBING
J 2
(-2500 3925);
DISPLAY 0.872340 (-2500 3925);
PAINT GREEN (-2500 3925);
DISPLAY INVISIBLE (-2500 3925);
FORCEPROP 1 LAST HDL_TAP TRUE
J 2
(-2825 3750);
DISPLAY 0.872340 (-2825 3750);
DISPLAY INVISIBLE (-2825 3750);
FORCEPROP 1 LAST PATH I70
J 2
(-2498 3875);
DISPLAY 0.872340 (-2498 3875);
PAINT GREEN (-2498 3875);
DISPLAY INVISIBLE (-2498 3875);
FORCEADD TAP..1
R 2
(-2500 4075);
FORCEPROP 3 LASTPIN (-2450 4075) SIG_NAME M_E_CPU1_SA_CA<0>
J 0
(-2440 4085);
DISPLAY 0.659574 (-2440 4085);
PAINT MONO (-2440 4085);
DISPLAY INVISIBLE (-2440 4085);
FORCEPROP 1 LASTPIN (-2450 4075) BN 0
J 2
(-2438 4083);
DISPLAY 0.680851 (-2438 4083);
PAINT GREEN (-2438 4083);
FORCEPROP 2 LAST CDS_LIB standard
J 0
(-2500 4075);
DISPLAY INVISIBLE (-2500 4075);
FORCEPROP 1 LAST BODY_TYPE PLUMBING
J 2
(-2500 4125);
DISPLAY 0.872340 (-2500 4125);
PAINT GREEN (-2500 4125);
DISPLAY INVISIBLE (-2500 4125);
FORCEPROP 1 LAST HDL_TAP TRUE
J 2
(-2825 3950);
DISPLAY 0.872340 (-2825 3950);
DISPLAY INVISIBLE (-2825 3950);
FORCEPROP 1 LAST PATH I71
J 2
(-2498 4075);
DISPLAY 0.872340 (-2498 4075);
PAINT GREEN (-2498 4075);
DISPLAY INVISIBLE (-2498 4075);
FORCEADD TAP..1
R 2
(-2500 4125);
FORCEPROP 3 LASTPIN (-2450 4125) SIG_NAME M_E_CPU1_SA_CA<1>
J 0
(-2440 4135);
DISPLAY 0.659574 (-2440 4135);
PAINT MONO (-2440 4135);
DISPLAY INVISIBLE (-2440 4135);
FORCEPROP 1 LASTPIN (-2450 4125) BN 1
J 2
(-2438 4133);
DISPLAY 0.680851 (-2438 4133);
PAINT GREEN (-2438 4133);
FORCEPROP 2 LAST CDS_LIB standard
J 0
(-2500 4125);
DISPLAY INVISIBLE (-2500 4125);
FORCEPROP 1 LAST BODY_TYPE PLUMBING
J 2
(-2500 4175);
DISPLAY 0.872340 (-2500 4175);
PAINT GREEN (-2500 4175);
DISPLAY INVISIBLE (-2500 4175);
FORCEPROP 1 LAST HDL_TAP TRUE
J 2
(-2825 4000);
DISPLAY 0.872340 (-2825 4000);
DISPLAY INVISIBLE (-2825 4000);
FORCEPROP 1 LAST PATH I72
J 2
(-2498 4125);
DISPLAY 0.872340 (-2498 4125);
PAINT GREEN (-2498 4125);
DISPLAY INVISIBLE (-2498 4125);
FORCEADD TAP..1
R 2
(-2500 4175);
FORCEPROP 3 LASTPIN (-2450 4175) SIG_NAME M_E_CPU1_SA_CA<2>
J 0
(-2440 4185);
DISPLAY 0.659574 (-2440 4185);
PAINT MONO (-2440 4185);
DISPLAY INVISIBLE (-2440 4185);
FORCEPROP 1 LASTPIN (-2450 4175) BN 2
J 2
(-2438 4183);
DISPLAY 0.680851 (-2438 4183);
PAINT GREEN (-2438 4183);
FORCEPROP 2 LAST CDS_LIB standard
J 0
(-2500 4175);
DISPLAY INVISIBLE (-2500 4175);
FORCEPROP 1 LAST BODY_TYPE PLUMBING
J 2
(-2500 4225);
DISPLAY 0.872340 (-2500 4225);
PAINT GREEN (-2500 4225);
DISPLAY INVISIBLE (-2500 4225);
FORCEPROP 1 LAST HDL_TAP TRUE
J 2
(-2825 4050);
DISPLAY 0.872340 (-2825 4050);
DISPLAY INVISIBLE (-2825 4050);
FORCEPROP 1 LAST PATH I73
J 2
(-2498 4175);
DISPLAY 0.872340 (-2498 4175);
PAINT GREEN (-2498 4175);
DISPLAY INVISIBLE (-2498 4175);
FORCEADD TAP..1
R 2
(-2500 4275);
FORCEPROP 3 LASTPIN (-2450 4275) SIG_NAME M_E_CPU1_SA_CA<4>
J 0
(-2440 4285);
DISPLAY 0.659574 (-2440 4285);
PAINT MONO (-2440 4285);
DISPLAY INVISIBLE (-2440 4285);
FORCEPROP 1 LASTPIN (-2450 4275) BN 4
J 2
(-2438 4283);
DISPLAY 0.680851 (-2438 4283);
PAINT GREEN (-2438 4283);
FORCEPROP 2 LAST CDS_LIB standard
J 0
(-2500 4275);
DISPLAY INVISIBLE (-2500 4275);
FORCEPROP 1 LAST BODY_TYPE PLUMBING
J 2
(-2500 4325);
DISPLAY 0.872340 (-2500 4325);
PAINT GREEN (-2500 4325);
DISPLAY INVISIBLE (-2500 4325);
FORCEPROP 1 LAST HDL_TAP TRUE
J 2
(-2825 4150);
DISPLAY 0.872340 (-2825 4150);
DISPLAY INVISIBLE (-2825 4150);
FORCEPROP 1 LAST PATH I74
J 2
(-2498 4275);
DISPLAY 0.872340 (-2498 4275);
PAINT GREEN (-2498 4275);
DISPLAY INVISIBLE (-2498 4275);
FORCEADD TAP..1
R 2
(-2500 4225);
FORCEPROP 3 LASTPIN (-2450 4225) SIG_NAME M_E_CPU1_SA_CA<3>
J 0
(-2440 4235);
DISPLAY 0.659574 (-2440 4235);
PAINT MONO (-2440 4235);
DISPLAY INVISIBLE (-2440 4235);
FORCEPROP 1 LASTPIN (-2450 4225) BN 3
J 2
(-2438 4233);
DISPLAY 0.680851 (-2438 4233);
PAINT GREEN (-2438 4233);
FORCEPROP 2 LAST CDS_LIB standard
J 0
(-2500 4225);
DISPLAY INVISIBLE (-2500 4225);
FORCEPROP 1 LAST BODY_TYPE PLUMBING
J 2
(-2500 4275);
DISPLAY 0.872340 (-2500 4275);
PAINT GREEN (-2500 4275);
DISPLAY INVISIBLE (-2500 4275);
FORCEPROP 1 LAST HDL_TAP TRUE
J 2
(-2825 4100);
DISPLAY 0.872340 (-2825 4100);
DISPLAY INVISIBLE (-2825 4100);
FORCEPROP 1 LAST PATH I75
J 2
(-2498 4225);
DISPLAY 0.872340 (-2498 4225);
PAINT GREEN (-2498 4225);
DISPLAY INVISIBLE (-2498 4225);
FORCEADD TAP..1
R 2
(-2500 4325);
FORCEPROP 3 LASTPIN (-2450 4325) SIG_NAME M_E_CPU1_SA_CA<5>
J 0
(-2440 4335);
DISPLAY 0.659574 (-2440 4335);
PAINT MONO (-2440 4335);
DISPLAY INVISIBLE (-2440 4335);
FORCEPROP 1 LASTPIN (-2450 4325) BN 5
J 2
(-2438 4333);
DISPLAY 0.680851 (-2438 4333);
PAINT GREEN (-2438 4333);
FORCEPROP 2 LAST CDS_LIB standard
J 0
(-2500 4325);
DISPLAY INVISIBLE (-2500 4325);
FORCEPROP 1 LAST BODY_TYPE PLUMBING
J 2
(-2500 4375);
DISPLAY 0.872340 (-2500 4375);
PAINT GREEN (-2500 4375);
DISPLAY INVISIBLE (-2500 4375);
FORCEPROP 1 LAST HDL_TAP TRUE
J 2
(-2825 4200);
DISPLAY 0.872340 (-2825 4200);
DISPLAY INVISIBLE (-2825 4200);
FORCEPROP 1 LAST PATH I76
J 2
(-2498 4325);
DISPLAY 0.872340 (-2498 4325);
PAINT GREEN (-2498 4325);
DISPLAY INVISIBLE (-2498 4325);
FORCEADD TAP..1
(-850 2325);
FORCEPROP 3 LASTPIN (-900 2325) SIG_NAME M_E_CPU1_SB_DQ<23>
J 0
(-890 2335);
DISPLAY 0.659574 (-890 2335);
PAINT MONO (-890 2335);
DISPLAY INVISIBLE (-890 2335);
FORCEPROP 1 LASTPIN (-900 2325) BN 23
J 0
(-912 2333);
DISPLAY 0.680851 (-912 2333);
PAINT GREEN (-912 2333);
FORCEPROP 2 LAST CDS_LIB standard
J 0
(-850 2325);
DISPLAY INVISIBLE (-850 2325);
FORCEPROP 1 LAST BODY_TYPE PLUMBING
J 0
(-850 2375);
DISPLAY 0.872340 (-850 2375);
PAINT GREEN (-850 2375);
DISPLAY INVISIBLE (-850 2375);
FORCEPROP 1 LAST HDL_TAP TRUE
J 0
(-525 2200);
DISPLAY 0.872340 (-525 2200);
DISPLAY INVISIBLE (-525 2200);
FORCEPROP 1 LAST PATH I77
J 0
(-852 2325);
DISPLAY 0.872340 (-852 2325);
PAINT GREEN (-852 2325);
DISPLAY INVISIBLE (-852 2325);
FORCEADD TAP..1
(-850 2525);
FORCEPROP 3 LASTPIN (-900 2525) SIG_NAME M_E_CPU1_SB_DQ<27>
J 0
(-890 2535);
DISPLAY 0.659574 (-890 2535);
PAINT MONO (-890 2535);
DISPLAY INVISIBLE (-890 2535);
FORCEPROP 1 LASTPIN (-900 2525) BN 27
J 0
(-912 2533);
DISPLAY 0.680851 (-912 2533);
PAINT GREEN (-912 2533);
FORCEPROP 2 LAST CDS_LIB standard
J 0
(-850 2525);
DISPLAY INVISIBLE (-850 2525);
FORCEPROP 1 LAST BODY_TYPE PLUMBING
J 0
(-850 2575);
DISPLAY 0.872340 (-850 2575);
PAINT GREEN (-850 2575);
DISPLAY INVISIBLE (-850 2575);
FORCEPROP 1 LAST HDL_TAP TRUE
J 0
(-525 2400);
DISPLAY 0.872340 (-525 2400);
DISPLAY INVISIBLE (-525 2400);
FORCEPROP 1 LAST PATH I78
J 0
(-852 2525);
DISPLAY 0.872340 (-852 2525);
PAINT GREEN (-852 2525);
DISPLAY INVISIBLE (-852 2525);
FORCEADD TAP..1
(-850 2425);
FORCEPROP 3 LASTPIN (-900 2425) SIG_NAME M_E_CPU1_SB_DQ<25>
J 0
(-890 2435);
DISPLAY 0.659574 (-890 2435);
PAINT MONO (-890 2435);
DISPLAY INVISIBLE (-890 2435);
FORCEPROP 1 LASTPIN (-900 2425) BN 25
J 0
(-912 2433);
DISPLAY 0.680851 (-912 2433);
PAINT GREEN (-912 2433);
FORCEPROP 2 LAST CDS_LIB standard
J 0
(-850 2425);
DISPLAY INVISIBLE (-850 2425);
FORCEPROP 1 LAST BODY_TYPE PLUMBING
J 0
(-850 2475);
DISPLAY 0.872340 (-850 2475);
PAINT GREEN (-850 2475);
DISPLAY INVISIBLE (-850 2475);
FORCEPROP 1 LAST HDL_TAP TRUE
J 0
(-525 2300);
DISPLAY 0.872340 (-525 2300);
DISPLAY INVISIBLE (-525 2300);
FORCEPROP 1 LAST PATH I79
J 0
(-852 2425);
DISPLAY 0.872340 (-852 2425);
PAINT GREEN (-852 2425);
DISPLAY INVISIBLE (-852 2425);
FORCEADD OFFPAGE..1
(-3325 1875);
FORCEPROP 2 LAST $XR0 107 
J 0
(-3577 1875);
DISPLAY 0.638298 (-3577 1875);
PAINT MONO (-3577 1875);
FORCEPROP 2 LAST CDS_LIB standard
J 0
(-3325 1875);
PAINT MONO (-3325 1875);
DISPLAY INVISIBLE (-3325 1875);
FORCEPROP 1 LAST OFFPAGE TRUE
J 0
(-3000 1750);
DISPLAY 0.872340 (-3000 1750);
DISPLAY INVISIBLE (-3000 1750);
FORCEPROP 1 LAST COMMENT_BODY TRUE
J 0
(-3200 1775);
DISPLAY 0.872340 (-3200 1775);
PAINT GREEN (-3200 1775);
DISPLAY INVISIBLE (-3200 1775);
FORCEPROP 2 LAST PATH I8
J 0
(-3275 1950);
DISPLAY 1.021277 (-3275 1950);
DISPLAY INVISIBLE (-3275 1950);
FORCEADD TAP..1
(-850 2475);
FORCEPROP 3 LASTPIN (-900 2475) SIG_NAME M_E_CPU1_SB_DQ<26>
J 0
(-890 2485);
DISPLAY 0.659574 (-890 2485);
PAINT MONO (-890 2485);
DISPLAY INVISIBLE (-890 2485);
FORCEPROP 1 LASTPIN (-900 2475) BN 26
J 0
(-912 2483);
DISPLAY 0.680851 (-912 2483);
PAINT GREEN (-912 2483);
FORCEPROP 2 LAST CDS_LIB standard
J 0
(-850 2475);
DISPLAY INVISIBLE (-850 2475);
FORCEPROP 1 LAST BODY_TYPE PLUMBING
J 0
(-850 2525);
DISPLAY 0.872340 (-850 2525);
PAINT GREEN (-850 2525);
DISPLAY INVISIBLE (-850 2525);
FORCEPROP 1 LAST HDL_TAP TRUE
J 0
(-525 2350);
DISPLAY 0.872340 (-525 2350);
DISPLAY INVISIBLE (-525 2350);
FORCEPROP 1 LAST PATH I80
J 0
(-852 2475);
DISPLAY 0.872340 (-852 2475);
PAINT GREEN (-852 2475);
DISPLAY INVISIBLE (-852 2475);
FORCEADD TAP..1
(-850 2375);
FORCEPROP 3 LASTPIN (-900 2375) SIG_NAME M_E_CPU1_SB_DQ<24>
J 0
(-890 2385);
DISPLAY 0.659574 (-890 2385);
PAINT MONO (-890 2385);
DISPLAY INVISIBLE (-890 2385);
FORCEPROP 1 LASTPIN (-900 2375) BN 24
J 0
(-912 2383);
DISPLAY 0.680851 (-912 2383);
PAINT GREEN (-912 2383);
FORCEPROP 2 LAST CDS_LIB standard
J 0
(-850 2375);
DISPLAY INVISIBLE (-850 2375);
FORCEPROP 1 LAST BODY_TYPE PLUMBING
J 0
(-850 2425);
DISPLAY 0.872340 (-850 2425);
PAINT GREEN (-850 2425);
DISPLAY INVISIBLE (-850 2425);
FORCEPROP 1 LAST HDL_TAP TRUE
J 0
(-525 2250);
DISPLAY 0.872340 (-525 2250);
DISPLAY INVISIBLE (-525 2250);
FORCEPROP 1 LAST PATH I81
J 0
(-852 2375);
DISPLAY 0.872340 (-852 2375);
PAINT GREEN (-852 2375);
DISPLAY INVISIBLE (-852 2375);
FORCEADD TAP..1
(-850 2725);
FORCEPROP 3 LASTPIN (-900 2725) SIG_NAME M_E_CPU1_SB_DQ<31>
J 0
(-890 2735);
DISPLAY 0.659574 (-890 2735);
PAINT MONO (-890 2735);
DISPLAY INVISIBLE (-890 2735);
FORCEPROP 1 LASTPIN (-900 2725) BN 31
J 0
(-912 2733);
DISPLAY 0.680851 (-912 2733);
PAINT GREEN (-912 2733);
FORCEPROP 2 LAST CDS_LIB standard
J 0
(-850 2725);
DISPLAY INVISIBLE (-850 2725);
FORCEPROP 1 LAST BODY_TYPE PLUMBING
J 0
(-850 2775);
DISPLAY 0.872340 (-850 2775);
PAINT GREEN (-850 2775);
DISPLAY INVISIBLE (-850 2775);
FORCEPROP 1 LAST HDL_TAP TRUE
J 0
(-525 2600);
DISPLAY 0.872340 (-525 2600);
DISPLAY INVISIBLE (-525 2600);
FORCEPROP 1 LAST PATH I82
J 0
(-852 2725);
DISPLAY 0.872340 (-852 2725);
PAINT GREEN (-852 2725);
DISPLAY INVISIBLE (-852 2725);
FORCEADD TAP..1
(-850 2675);
FORCEPROP 3 LASTPIN (-900 2675) SIG_NAME M_E_CPU1_SB_DQ<30>
J 0
(-890 2685);
DISPLAY 0.659574 (-890 2685);
PAINT MONO (-890 2685);
DISPLAY INVISIBLE (-890 2685);
FORCEPROP 1 LASTPIN (-900 2675) BN 30
J 0
(-912 2683);
DISPLAY 0.680851 (-912 2683);
PAINT GREEN (-912 2683);
FORCEPROP 2 LAST CDS_LIB standard
J 0
(-850 2675);
DISPLAY INVISIBLE (-850 2675);
FORCEPROP 1 LAST BODY_TYPE PLUMBING
J 0
(-850 2725);
DISPLAY 0.872340 (-850 2725);
PAINT GREEN (-850 2725);
DISPLAY INVISIBLE (-850 2725);
FORCEPROP 1 LAST HDL_TAP TRUE
J 0
(-525 2550);
DISPLAY 0.872340 (-525 2550);
DISPLAY INVISIBLE (-525 2550);
FORCEPROP 1 LAST PATH I83
J 0
(-852 2675);
DISPLAY 0.872340 (-852 2675);
PAINT GREEN (-852 2675);
DISPLAY INVISIBLE (-852 2675);
FORCEADD TAP..1
(-850 2625);
FORCEPROP 3 LASTPIN (-900 2625) SIG_NAME M_E_CPU1_SB_DQ<29>
J 0
(-890 2635);
DISPLAY 0.659574 (-890 2635);
PAINT MONO (-890 2635);
DISPLAY INVISIBLE (-890 2635);
FORCEPROP 1 LASTPIN (-900 2625) BN 29
J 0
(-912 2633);
DISPLAY 0.680851 (-912 2633);
PAINT GREEN (-912 2633);
FORCEPROP 2 LAST CDS_LIB standard
J 0
(-850 2625);
DISPLAY INVISIBLE (-850 2625);
FORCEPROP 1 LAST BODY_TYPE PLUMBING
J 0
(-850 2675);
DISPLAY 0.872340 (-850 2675);
PAINT GREEN (-850 2675);
DISPLAY INVISIBLE (-850 2675);
FORCEPROP 1 LAST HDL_TAP TRUE
J 0
(-525 2500);
DISPLAY 0.872340 (-525 2500);
DISPLAY INVISIBLE (-525 2500);
FORCEPROP 1 LAST PATH I84
J 0
(-852 2625);
DISPLAY 0.872340 (-852 2625);
PAINT GREEN (-852 2625);
DISPLAY INVISIBLE (-852 2625);
FORCEADD TAP..1
(-850 2575);
FORCEPROP 3 LASTPIN (-900 2575) SIG_NAME M_E_CPU1_SB_DQ<28>
J 0
(-890 2585);
DISPLAY 0.659574 (-890 2585);
PAINT MONO (-890 2585);
DISPLAY INVISIBLE (-890 2585);
FORCEPROP 1 LASTPIN (-900 2575) BN 28
J 0
(-912 2583);
DISPLAY 0.680851 (-912 2583);
PAINT GREEN (-912 2583);
FORCEPROP 2 LAST CDS_LIB standard
J 0
(-850 2575);
DISPLAY INVISIBLE (-850 2575);
FORCEPROP 1 LAST BODY_TYPE PLUMBING
J 0
(-850 2625);
DISPLAY 0.872340 (-850 2625);
PAINT GREEN (-850 2625);
DISPLAY INVISIBLE (-850 2625);
FORCEPROP 1 LAST HDL_TAP TRUE
J 0
(-525 2450);
DISPLAY 0.872340 (-525 2450);
DISPLAY INVISIBLE (-525 2450);
FORCEPROP 1 LAST PATH I85
J 0
(-852 2575);
DISPLAY 0.872340 (-852 2575);
PAINT GREEN (-852 2575);
DISPLAY INVISIBLE (-852 2575);
FORCEADD TAP..1
(-850 2825);
FORCEPROP 3 LASTPIN (-900 2825) SIG_NAME M_E_CPU1_SA_DQ<0>
J 0
(-890 2835);
DISPLAY 0.659574 (-890 2835);
PAINT MONO (-890 2835);
DISPLAY INVISIBLE (-890 2835);
FORCEPROP 1 LASTPIN (-900 2825) BN 0
J 0
(-912 2833);
DISPLAY 0.680851 (-912 2833);
PAINT GREEN (-912 2833);
FORCEPROP 2 LAST CDS_LIB standard
J 0
(-850 2825);
PAINT MONO (-850 2825);
DISPLAY INVISIBLE (-850 2825);
FORCEPROP 1 LAST BODY_TYPE PLUMBING
J 0
(-850 2875);
DISPLAY 0.872340 (-850 2875);
PAINT GREEN (-850 2875);
DISPLAY INVISIBLE (-850 2875);
FORCEPROP 1 LAST HDL_TAP TRUE
J 0
(-525 2700);
DISPLAY 0.872340 (-525 2700);
DISPLAY INVISIBLE (-525 2700);
FORCEPROP 1 LAST PATH I86
J 0
(-852 2825);
DISPLAY 0.872340 (-852 2825);
PAINT GREEN (-852 2825);
DISPLAY INVISIBLE (-852 2825);
FORCEADD TAP..1
(-850 2925);
FORCEPROP 3 LASTPIN (-900 2925) SIG_NAME M_E_CPU1_SA_DQ<2>
J 0
(-890 2935);
DISPLAY 0.659574 (-890 2935);
PAINT MONO (-890 2935);
DISPLAY INVISIBLE (-890 2935);
FORCEPROP 1 LASTPIN (-900 2925) BN 2
J 0
(-912 2933);
DISPLAY 0.680851 (-912 2933);
PAINT GREEN (-912 2933);
FORCEPROP 2 LAST CDS_LIB standard
J 0
(-850 2925);
PAINT MONO (-850 2925);
DISPLAY INVISIBLE (-850 2925);
FORCEPROP 1 LAST BODY_TYPE PLUMBING
J 0
(-850 2975);
DISPLAY 0.872340 (-850 2975);
PAINT GREEN (-850 2975);
DISPLAY INVISIBLE (-850 2975);
FORCEPROP 1 LAST HDL_TAP TRUE
J 0
(-525 2800);
DISPLAY 0.872340 (-525 2800);
DISPLAY INVISIBLE (-525 2800);
FORCEPROP 1 LAST PATH I87
J 0
(-852 2925);
DISPLAY 0.872340 (-852 2925);
PAINT GREEN (-852 2925);
DISPLAY INVISIBLE (-852 2925);
FORCEADD TAP..1
(-850 2875);
FORCEPROP 3 LASTPIN (-900 2875) SIG_NAME M_E_CPU1_SA_DQ<1>
J 0
(-890 2885);
DISPLAY 0.659574 (-890 2885);
PAINT MONO (-890 2885);
DISPLAY INVISIBLE (-890 2885);
FORCEPROP 1 LASTPIN (-900 2875) BN 1
J 0
(-912 2883);
DISPLAY 0.680851 (-912 2883);
PAINT GREEN (-912 2883);
FORCEPROP 2 LAST CDS_LIB standard
J 0
(-850 2875);
PAINT MONO (-850 2875);
DISPLAY INVISIBLE (-850 2875);
FORCEPROP 1 LAST BODY_TYPE PLUMBING
J 0
(-850 2925);
DISPLAY 0.872340 (-850 2925);
PAINT GREEN (-850 2925);
DISPLAY INVISIBLE (-850 2925);
FORCEPROP 1 LAST HDL_TAP TRUE
J 0
(-525 2750);
DISPLAY 0.872340 (-525 2750);
DISPLAY INVISIBLE (-525 2750);
FORCEPROP 1 LAST PATH I88
J 0
(-852 2875);
DISPLAY 0.872340 (-852 2875);
PAINT GREEN (-852 2875);
DISPLAY INVISIBLE (-852 2875);
FORCEADD TAP..1
(-850 3025);
FORCEPROP 3 LASTPIN (-900 3025) SIG_NAME M_E_CPU1_SA_DQ<4>
J 0
(-890 3035);
DISPLAY 0.659574 (-890 3035);
PAINT MONO (-890 3035);
DISPLAY INVISIBLE (-890 3035);
FORCEPROP 1 LASTPIN (-900 3025) BN 4
J 0
(-912 3033);
DISPLAY 0.680851 (-912 3033);
PAINT GREEN (-912 3033);
FORCEPROP 2 LAST CDS_LIB standard
J 0
(-850 3025);
PAINT MONO (-850 3025);
DISPLAY INVISIBLE (-850 3025);
FORCEPROP 1 LAST BODY_TYPE PLUMBING
J 0
(-850 3075);
DISPLAY 0.872340 (-850 3075);
PAINT GREEN (-850 3075);
DISPLAY INVISIBLE (-850 3075);
FORCEPROP 1 LAST HDL_TAP TRUE
J 0
(-525 2900);
DISPLAY 0.872340 (-525 2900);
DISPLAY INVISIBLE (-525 2900);
FORCEPROP 1 LAST PATH I89
J 0
(-852 3025);
DISPLAY 0.872340 (-852 3025);
PAINT GREEN (-852 3025);
DISPLAY INVISIBLE (-852 3025);
FORCEADD OFFPAGE..1
(-3325 1825);
FORCEPROP 2 LAST $XR7 113 
J 0
(-3817 1861);
DISPLAY 0.638298 (-3817 1861);
PAINT MONO (-3817 1861);
FORCEPROP 2 LAST $XR6 112 
J 0
(-3697 1861);
DISPLAY 0.638298 (-3697 1861);
PAINT MONO (-3697 1861);
FORCEPROP 2 LAST $XR5 111 
J 0
(-3817 1789);
DISPLAY 0.638298 (-3817 1789);
PAINT MONO (-3817 1789);
FORCEPROP 2 LAST $XR4 110 
J 0
(-3697 1789);
DISPLAY 0.638298 (-3697 1789);
PAINT MONO (-3697 1789);
FORCEPROP 2 LAST $XR3 109 
J 0
(-3577 1789);
DISPLAY 0.638298 (-3577 1789);
PAINT MONO (-3577 1789);
FORCEPROP 2 LAST $XR2 108 
J 0
(-3817 1825);
DISPLAY 0.638298 (-3817 1825);
PAINT MONO (-3817 1825);
FORCEPROP 2 LAST $XR1 106 
J 0
(-3697 1825);
DISPLAY 0.638298 (-3697 1825);
PAINT MONO (-3697 1825);
FORCEPROP 2 LAST $XR0 230 
J 0
(-3577 1825);
DISPLAY 0.638298 (-3577 1825);
PAINT MONO (-3577 1825);
FORCEPROP 2 LAST CDS_LIB standard
J 0
(-3325 1825);
PAINT MONO (-3325 1825);
DISPLAY INVISIBLE (-3325 1825);
FORCEPROP 1 LAST OFFPAGE TRUE
J 0
(-3000 1700);
DISPLAY 0.872340 (-3000 1700);
DISPLAY INVISIBLE (-3000 1700);
FORCEPROP 1 LAST COMMENT_BODY TRUE
J 0
(-3200 1725);
DISPLAY 0.872340 (-3200 1725);
PAINT GREEN (-3200 1725);
DISPLAY INVISIBLE (-3200 1725);
FORCEPROP 2 LAST PATH I9
J 0
(-3275 1900);
DISPLAY 1.021277 (-3275 1900);
DISPLAY INVISIBLE (-3275 1900);
FORCEADD TAP..1
(-850 2975);
FORCEPROP 3 LASTPIN (-900 2975) SIG_NAME M_E_CPU1_SA_DQ<3>
J 0
(-890 2985);
DISPLAY 0.659574 (-890 2985);
PAINT MONO (-890 2985);
DISPLAY INVISIBLE (-890 2985);
FORCEPROP 1 LASTPIN (-900 2975) BN 3
J 0
(-912 2983);
DISPLAY 0.680851 (-912 2983);
PAINT GREEN (-912 2983);
FORCEPROP 2 LAST CDS_LIB standard
J 0
(-850 2975);
PAINT MONO (-850 2975);
DISPLAY INVISIBLE (-850 2975);
FORCEPROP 1 LAST BODY_TYPE PLUMBING
J 0
(-850 3025);
DISPLAY 0.872340 (-850 3025);
PAINT GREEN (-850 3025);
DISPLAY INVISIBLE (-850 3025);
FORCEPROP 1 LAST HDL_TAP TRUE
J 0
(-525 2850);
DISPLAY 0.872340 (-525 2850);
DISPLAY INVISIBLE (-525 2850);
FORCEPROP 1 LAST PATH I90
J 0
(-852 2975);
DISPLAY 0.872340 (-852 2975);
PAINT GREEN (-852 2975);
DISPLAY INVISIBLE (-852 2975);
FORCEADD TAP..1
(-850 3275);
FORCEPROP 3 LASTPIN (-900 3275) SIG_NAME M_E_CPU1_SA_DQ<9>
J 0
(-890 3285);
DISPLAY 0.659574 (-890 3285);
PAINT MONO (-890 3285);
DISPLAY INVISIBLE (-890 3285);
FORCEPROP 1 LASTPIN (-900 3275) BN 9
J 0
(-912 3283);
DISPLAY 0.680851 (-912 3283);
PAINT GREEN (-912 3283);
FORCEPROP 2 LAST CDS_LIB standard
J 0
(-850 3275);
PAINT MONO (-850 3275);
DISPLAY INVISIBLE (-850 3275);
FORCEPROP 1 LAST BODY_TYPE PLUMBING
J 0
(-850 3325);
DISPLAY 0.872340 (-850 3325);
PAINT GREEN (-850 3325);
DISPLAY INVISIBLE (-850 3325);
FORCEPROP 1 LAST HDL_TAP TRUE
J 0
(-525 3150);
DISPLAY 0.872340 (-525 3150);
DISPLAY INVISIBLE (-525 3150);
FORCEPROP 1 LAST PATH I91
J 0
(-852 3275);
DISPLAY 0.872340 (-852 3275);
PAINT GREEN (-852 3275);
DISPLAY INVISIBLE (-852 3275);
FORCEADD TAP..1
(-850 3125);
FORCEPROP 3 LASTPIN (-900 3125) SIG_NAME M_E_CPU1_SA_DQ<6>
J 0
(-890 3135);
DISPLAY 0.659574 (-890 3135);
PAINT MONO (-890 3135);
DISPLAY INVISIBLE (-890 3135);
FORCEPROP 1 LASTPIN (-900 3125) BN 6
J 0
(-912 3133);
DISPLAY 0.680851 (-912 3133);
PAINT GREEN (-912 3133);
FORCEPROP 2 LAST CDS_LIB standard
J 0
(-850 3125);
PAINT MONO (-850 3125);
DISPLAY INVISIBLE (-850 3125);
FORCEPROP 1 LAST BODY_TYPE PLUMBING
J 0
(-850 3175);
DISPLAY 0.872340 (-850 3175);
PAINT GREEN (-850 3175);
DISPLAY INVISIBLE (-850 3175);
FORCEPROP 1 LAST HDL_TAP TRUE
J 0
(-525 3000);
DISPLAY 0.872340 (-525 3000);
DISPLAY INVISIBLE (-525 3000);
FORCEPROP 1 LAST PATH I92
J 0
(-852 3125);
DISPLAY 0.872340 (-852 3125);
PAINT GREEN (-852 3125);
DISPLAY INVISIBLE (-852 3125);
FORCEADD TAP..1
(-850 3225);
FORCEPROP 3 LASTPIN (-900 3225) SIG_NAME M_E_CPU1_SA_DQ<8>
J 0
(-890 3235);
DISPLAY 0.659574 (-890 3235);
PAINT MONO (-890 3235);
DISPLAY INVISIBLE (-890 3235);
FORCEPROP 1 LASTPIN (-900 3225) BN 8
J 0
(-912 3233);
DISPLAY 0.680851 (-912 3233);
PAINT GREEN (-912 3233);
FORCEPROP 2 LAST CDS_LIB standard
J 0
(-850 3225);
PAINT MONO (-850 3225);
DISPLAY INVISIBLE (-850 3225);
FORCEPROP 1 LAST BODY_TYPE PLUMBING
J 0
(-850 3275);
DISPLAY 0.872340 (-850 3275);
PAINT GREEN (-850 3275);
DISPLAY INVISIBLE (-850 3275);
FORCEPROP 1 LAST HDL_TAP TRUE
J 0
(-525 3100);
DISPLAY 0.872340 (-525 3100);
DISPLAY INVISIBLE (-525 3100);
FORCEPROP 1 LAST PATH I93
J 0
(-852 3225);
DISPLAY 0.872340 (-852 3225);
PAINT GREEN (-852 3225);
DISPLAY INVISIBLE (-852 3225);
FORCEADD TAP..1
(-850 3175);
FORCEPROP 3 LASTPIN (-900 3175) SIG_NAME M_E_CPU1_SA_DQ<7>
J 0
(-890 3185);
DISPLAY 0.659574 (-890 3185);
PAINT MONO (-890 3185);
DISPLAY INVISIBLE (-890 3185);
FORCEPROP 1 LASTPIN (-900 3175) BN 7
J 0
(-912 3183);
DISPLAY 0.680851 (-912 3183);
PAINT GREEN (-912 3183);
FORCEPROP 2 LAST CDS_LIB standard
J 0
(-850 3175);
PAINT MONO (-850 3175);
DISPLAY INVISIBLE (-850 3175);
FORCEPROP 1 LAST BODY_TYPE PLUMBING
J 0
(-850 3225);
DISPLAY 0.872340 (-850 3225);
PAINT GREEN (-850 3225);
DISPLAY INVISIBLE (-850 3225);
FORCEPROP 1 LAST HDL_TAP TRUE
J 0
(-525 3050);
DISPLAY 0.872340 (-525 3050);
DISPLAY INVISIBLE (-525 3050);
FORCEPROP 1 LAST PATH I94
J 0
(-852 3175);
DISPLAY 0.872340 (-852 3175);
PAINT GREEN (-852 3175);
DISPLAY INVISIBLE (-852 3175);
FORCEADD TAP..1
(-850 3075);
FORCEPROP 3 LASTPIN (-900 3075) SIG_NAME M_E_CPU1_SA_DQ<5>
J 0
(-890 3085);
DISPLAY 0.659574 (-890 3085);
PAINT MONO (-890 3085);
DISPLAY INVISIBLE (-890 3085);
FORCEPROP 1 LASTPIN (-900 3075) BN 5
J 0
(-912 3083);
DISPLAY 0.680851 (-912 3083);
PAINT GREEN (-912 3083);
FORCEPROP 2 LAST CDS_LIB standard
J 0
(-850 3075);
PAINT MONO (-850 3075);
DISPLAY INVISIBLE (-850 3075);
FORCEPROP 1 LAST BODY_TYPE PLUMBING
J 0
(-850 3125);
DISPLAY 0.872340 (-850 3125);
PAINT GREEN (-850 3125);
DISPLAY INVISIBLE (-850 3125);
FORCEPROP 1 LAST HDL_TAP TRUE
J 0
(-525 2950);
DISPLAY 0.872340 (-525 2950);
DISPLAY INVISIBLE (-525 2950);
FORCEPROP 1 LAST PATH I95
J 0
(-852 3075);
DISPLAY 0.872340 (-852 3075);
PAINT GREEN (-852 3075);
DISPLAY INVISIBLE (-852 3075);
FORCEADD TAP..1
(-850 3325);
FORCEPROP 3 LASTPIN (-900 3325) SIG_NAME M_E_CPU1_SA_DQ<10>
J 0
(-890 3335);
DISPLAY 0.659574 (-890 3335);
PAINT MONO (-890 3335);
DISPLAY INVISIBLE (-890 3335);
FORCEPROP 1 LASTPIN (-900 3325) BN 10
J 0
(-912 3333);
DISPLAY 0.680851 (-912 3333);
PAINT GREEN (-912 3333);
FORCEPROP 2 LAST CDS_LIB standard
J 0
(-850 3325);
PAINT MONO (-850 3325);
DISPLAY INVISIBLE (-850 3325);
FORCEPROP 1 LAST BODY_TYPE PLUMBING
J 0
(-850 3375);
DISPLAY 0.872340 (-850 3375);
PAINT GREEN (-850 3375);
DISPLAY INVISIBLE (-850 3375);
FORCEPROP 1 LAST HDL_TAP TRUE
J 0
(-525 3200);
DISPLAY 0.872340 (-525 3200);
DISPLAY INVISIBLE (-525 3200);
FORCEPROP 1 LAST PATH I96
J 0
(-852 3325);
DISPLAY 0.872340 (-852 3325);
PAINT GREEN (-852 3325);
DISPLAY INVISIBLE (-852 3325);
FORCEADD TAP..1
(-850 3375);
FORCEPROP 3 LASTPIN (-900 3375) SIG_NAME M_E_CPU1_SA_DQ<11>
J 0
(-890 3385);
DISPLAY 0.659574 (-890 3385);
PAINT MONO (-890 3385);
DISPLAY INVISIBLE (-890 3385);
FORCEPROP 1 LASTPIN (-900 3375) BN 11
J 0
(-912 3383);
DISPLAY 0.680851 (-912 3383);
PAINT GREEN (-912 3383);
FORCEPROP 2 LAST CDS_LIB standard
J 0
(-850 3375);
PAINT MONO (-850 3375);
DISPLAY INVISIBLE (-850 3375);
FORCEPROP 1 LAST BODY_TYPE PLUMBING
J 0
(-850 3425);
DISPLAY 0.872340 (-850 3425);
PAINT GREEN (-850 3425);
DISPLAY INVISIBLE (-850 3425);
FORCEPROP 1 LAST HDL_TAP TRUE
J 0
(-525 3250);
DISPLAY 0.872340 (-525 3250);
DISPLAY INVISIBLE (-525 3250);
FORCEPROP 1 LAST PATH I97
J 0
(-852 3375);
DISPLAY 0.872340 (-852 3375);
PAINT GREEN (-852 3375);
DISPLAY INVISIBLE (-852 3375);
FORCEADD TAP..1
(-850 3425);
FORCEPROP 3 LASTPIN (-900 3425) SIG_NAME M_E_CPU1_SA_DQ<12>
J 0
(-890 3435);
DISPLAY 0.659574 (-890 3435);
PAINT MONO (-890 3435);
DISPLAY INVISIBLE (-890 3435);
FORCEPROP 1 LASTPIN (-900 3425) BN 12
J 0
(-912 3433);
DISPLAY 0.680851 (-912 3433);
PAINT GREEN (-912 3433);
FORCEPROP 2 LAST CDS_LIB standard
J 0
(-850 3425);
PAINT MONO (-850 3425);
DISPLAY INVISIBLE (-850 3425);
FORCEPROP 1 LAST BODY_TYPE PLUMBING
J 0
(-850 3475);
DISPLAY 0.872340 (-850 3475);
PAINT GREEN (-850 3475);
DISPLAY INVISIBLE (-850 3475);
FORCEPROP 1 LAST HDL_TAP TRUE
J 0
(-525 3300);
DISPLAY 0.872340 (-525 3300);
DISPLAY INVISIBLE (-525 3300);
FORCEPROP 1 LAST PATH I98
J 0
(-852 3425);
DISPLAY 0.872340 (-852 3425);
PAINT GREEN (-852 3425);
DISPLAY INVISIBLE (-852 3425);
FORCEADD TAP..1
(-850 3575);
FORCEPROP 3 LASTPIN (-900 3575) SIG_NAME M_E_CPU1_SA_DQ<15>
J 0
(-890 3585);
DISPLAY 0.659574 (-890 3585);
PAINT MONO (-890 3585);
DISPLAY INVISIBLE (-890 3585);
FORCEPROP 1 LASTPIN (-900 3575) BN 15
J 0
(-912 3583);
DISPLAY 0.680851 (-912 3583);
PAINT GREEN (-912 3583);
FORCEPROP 2 LAST CDS_LIB standard
J 0
(-850 3575);
PAINT MONO (-850 3575);
DISPLAY INVISIBLE (-850 3575);
FORCEPROP 1 LAST BODY_TYPE PLUMBING
J 0
(-850 3625);
DISPLAY 0.872340 (-850 3625);
PAINT GREEN (-850 3625);
DISPLAY INVISIBLE (-850 3625);
FORCEPROP 1 LAST HDL_TAP TRUE
J 0
(-525 3450);
DISPLAY 0.872340 (-525 3450);
DISPLAY INVISIBLE (-525 3450);
FORCEPROP 1 LAST PATH I99
J 0
(-852 3575);
DISPLAY 0.872340 (-852 3575);
PAINT GREEN (-852 3575);
DISPLAY INVISIBLE (-852 3575);
FORCEADD CAD_NOTE..1
(1000 -75);
FORCEPROP 0 LAST S1 PLACE THE BYPASS CAPS CLOSE TO DIMM
J 0
(875 -200);
DISPLAY 1.021277 (875 -200);
PAINT WHITE (875 -200);
FORCEPROP 2 LAST CDS_LIB logical_power
J 0
(1000 -75);
PAINT MONO (1000 -75);
DISPLAY INVISIBLE (1000 -75);
FORCEPROP 1 LAST COMMENT_BODY TRUE
J 0
(1025 25);
DISPLAY 0.978723 (1025 25);
DISPLAY INVISIBLE (1025 25);
FORCEADD QUANTA_TITLE_BLOCK_C..1
(5475 -1375);
FORCEPROP 0 LAST CDS_CON_LAST_MODIFIED Fri Aug 25 14:01:27 2023
J 0
(3590 -1360);
PAINT MONO (3590 -1360);
DISPLAY INVISIBLE (3590 -1360);
FORCEPROP 1 LAST CUSTOM_TXT_CDS <CON_LAST_MODIFIED>
J 0
(3590 -1360);
DISPLAY 0.978723 (3590 -1360);
FORCEPROP 2 LAST CUSTOM_TXT_CDS <XR_PAGE_TITLE>
J 0
(-2415 3875);
DISPLAY 0.638298 (-2415 3875);
PAINT PINK (-2415 3875);
DISPLAY INVISIBLE (-2415 3875);
FORCEPROP 2 LAST CUSTOM_TXT_CDS <Q_NUMBER>
J 0
(4072 -1272);
DISPLAY 1.212766 (4072 -1272);
FORCEPROP 1 LAST CUSTOM_TXT_CDS <NAME_2>
J 0
(2300 -1325);
FORCEPROP 1 LAST CUSTOM_TXT_CDS <NAME_1>
J 0
(2300 -1200);
FORCEPROP 1 LAST CUSTOM_TXT_CDS <Q_PROJ>
J 0
(3093 -1273);
DISPLAY 1.212766 (3093 -1273);
FORCEPROP 1 LAST CUSTOM_TXT_CDS <Q_REV>
J 0
(5291 -1272);
DISPLAY 1.212766 (5291 -1272);
FORCEPROP 1 LAST CUSTOM_TXT_CDS <CON_PAGE_NUM> OF <CON_TOTAL_PAGES>
J 0
(5029 -1357);
DISPLAY 0.978723 (5029 -1357);
FORCEPROP 1 LAST Q_TITLE DDR5 - CPU1 CHE DIMM2(BLACK)
J 0
(-3891 -1349);
DISPLAY 2.446809 (-3891 -1349);
PAINT GREEN (-3891 -1349);
FORCEPROP 1 LAST Q_DEPT 
J 1
(1712 -1326);
DISPLAY 1.957447 (1712 -1326);
PAINT GREEN (1712 -1326);
FORCEPROP 2 LAST CDS_XR_PAGE_TITLE CR-107 : @S9S_MB_2U_LIB.S9S_MB_2U(SCH_1):PAGE107
J 0
(-2415 3875);
DISPLAY 0.638298 (-2415 3875);
PAINT PINK (-2415 3875);
DISPLAY INVISIBLE (-2415 3875);
FORCEPROP 1 LAST COMMENT_BODY TRUE
J 0
(5487 -1388);
DISPLAY 0.978723 (5487 -1388);
PAINT GREEN (5487 -1388);
DISPLAY INVISIBLE (5487 -1388);
FORCEPROP 2 LAST CDS_LIB pure_quanta
J 0
(5475 -1375);
PAINT MONO (5475 -1375);
DISPLAY INVISIBLE (5475 -1375);
FORCEPROP 1 LAST CDS_LMAN_SYM_OUTLINE -9475,6775,100,-125
J 0
(5475 -1375);
DISPLAY 0.468085 (5475 -1375);
PAINT GREEN (5475 -1375);
DISPLAY INVISIBLE (5475 -1375);
FORCEPROP 2 LAST PAGE_BORDER TRUE
J 0
(-2415 3875);
DISPLAY 0.638298 (-2415 3875);
PAINT PINK (-2415 3875);
DISPLAY INVISIBLE (-2415 3875);
WIRE 17 -1 (-800 4400)(-75 4400);
FORCEPROP 2 LAST SIG_NAME M_E_CPU1_SA_DQ<31:0>
J 0
(-735 4410);
DISPLAY 0.680851 (-735 4410);
PAINT WHITE (-735 4410);
WIRE 17 -1 (-3375 3000)(-2550 3000);
FORCEPROP 2 LAST SIG_NAME M_E_CPU1_SA_CB<7:0>
J 0
(-3285 3010);
DISPLAY 0.680851 (-3285 3010);
PAINT WHITE (-3285 3010);
WIRE 17 -1 (-2550 2850)(-2550 2900);
WIRE 17 -1 (-2550 2800)(-2550 2850);
WIRE 17 -1 (-2550 2900)(-2550 2950);
WIRE 17 -1 (-2550 2950)(-2550 3000);
WIRE 17 -1 (-2550 2750)(-2550 2800);
WIRE 17 -1 (-2550 2700)(-2550 2750);
WIRE 17 -1 (-2550 2650)(-2550 2700);
WIRE 17 -1 (-3375 2550)(-2550 2550);
FORCEPROP 2 LAST SIG_NAME M_E_CPU1_SB_CB<7:0>
J 0
(-3285 2560);
DISPLAY 0.680851 (-3285 2560);
PAINT WHITE (-3285 2560);
WIRE 17 -1 (-2550 4100)(-2550 4150);
WIRE 17 -1 (-2550 4150)(-2550 4200);
WIRE 17 -1 (-2550 4200)(-2550 4250);
WIRE 17 -1 (-2550 4250)(-2550 4300);
WIRE 17 -1 (-2550 4300)(-2550 4350);
WIRE 17 -1 (-2550 4350)(-2550 4400);
WIRE 17 -1 (-3375 4400)(-2550 4400);
FORCEPROP 2 LAST SIG_NAME M_E_CPU1_SA_CA<6:0>
J 0
(-3285 4410);
DISPLAY 0.680851 (-3285 4410);
PAINT WHITE (-3285 4410);
WIRE 17 -1 (-2550 3700)(-2550 3750);
WIRE 17 -1 (-2550 3750)(-2550 3800);
WIRE 17 -1 (-2550 3800)(-2550 3850);
WIRE 17 -1 (-2550 3850)(-2550 3900);
WIRE 17 -1 (-2550 3900)(-2550 3950);
WIRE 17 -1 (-2550 3950)(-2550 4000);
WIRE 17 -1 (-3375 4000)(-2550 4000);
FORCEPROP 2 LAST SIG_NAME M_E_CPU1_SB_CA<6:0>
J 0
(-3285 4010);
DISPLAY 0.680851 (-3285 4010);
PAINT WHITE (-3285 4010);
WIRE 17 -1 (-2550 2500)(-2550 2550);
WIRE 17 -1 (-2550 2450)(-2550 2500);
WIRE 17 -1 (-2550 2400)(-2550 2450);
WIRE 17 -1 (-2550 2350)(-2550 2400);
WIRE 17 -1 (-2550 2300)(-2550 2350);
WIRE 17 -1 (-2550 2250)(-2550 2300);
WIRE 17 -1 (-2550 2200)(-2550 2250);
WIRE 17 -1 (-800 4350)(-800 4400);
WIRE 17 -1 (-800 4300)(-800 4350);
WIRE 17 -1 (-800 4250)(-800 4300);
WIRE 17 -1 (-800 4200)(-800 4250);
WIRE 17 -1 (-800 4150)(-800 4200);
WIRE 17 -1 (-800 4100)(-800 4150);
WIRE 17 -1 (-800 4050)(-800 4100);
WIRE 17 -1 (-800 4000)(-800 4050);
WIRE 17 -1 (-800 3950)(-800 4000);
WIRE 17 -1 (-800 3900)(-800 3950);
WIRE 17 -1 (-800 3850)(-800 3900);
WIRE 17 -1 (-800 3800)(-800 3850);
WIRE 17 -1 (-800 3750)(-800 3800);
WIRE 17 -1 (-800 3700)(-800 3750);
WIRE 17 -1 (-800 3650)(-800 3700);
WIRE 17 -1 (-800 3600)(-800 3650);
WIRE 17 -1 (-800 3550)(-800 3600);
WIRE 17 -1 (-800 3500)(-800 3550);
WIRE 17 -1 (-800 3450)(-800 3500);
WIRE 17 -1 (-800 3400)(-800 3450);
WIRE 17 -1 (-800 3350)(-800 3400);
WIRE 17 -1 (-800 3300)(-800 3350);
WIRE 17 -1 (-800 3250)(-800 3300);
WIRE 17 -1 (-800 3200)(-800 3250);
WIRE 17 -1 (-800 3150)(-800 3200);
WIRE 17 -1 (-800 3100)(-800 3150);
WIRE 17 -1 (-800 3050)(-800 3100);
WIRE 17 -1 (-800 3000)(-800 3050);
WIRE 17 -1 (-800 2950)(-800 3000);
WIRE 17 -1 (-800 2900)(-800 2950);
WIRE 17 -1 (-800 2850)(-800 2900);
WIRE 17 -1 (-800 2650)(-800 2700);
WIRE 17 -1 (-800 2600)(-800 2650);
WIRE 17 -1 (-800 2700)(-800 2750);
WIRE 17 -1 (-800 2750)(-75 2750);
FORCEPROP 2 LAST SIG_NAME M_E_CPU1_SB_DQ<31:0>
J 0
(-735 2760);
DISPLAY 0.680851 (-735 2760);
PAINT WHITE (-735 2760);
WIRE 17 -1 (-800 2550)(-800 2600);
WIRE 17 -1 (-800 2500)(-800 2550);
WIRE 17 -1 (-800 2450)(-800 2500);
WIRE 17 -1 (-800 2400)(-800 2450);
WIRE 17 -1 (-800 2350)(-800 2400);
WIRE 17 -1 (-800 2300)(-800 2350);
WIRE 17 -1 (-800 2250)(-800 2300);
WIRE 17 -1 (-800 2200)(-800 2250);
WIRE 17 -1 (-800 2150)(-800 2200);
WIRE 17 -1 (-800 2100)(-800 2150);
WIRE 17 -1 (-800 2050)(-800 2100);
WIRE 17 -1 (-800 2000)(-800 2050);
WIRE 17 -1 (-800 1950)(-800 2000);
WIRE 17 -1 (-800 1900)(-800 1950);
WIRE 17 -1 (-800 1850)(-800 1900);
WIRE 17 -1 (-800 1800)(-800 1850);
WIRE 17 -1 (-800 1750)(-800 1800);
WIRE 17 -1 (-800 1700)(-800 1750);
WIRE 17 -1 (-800 1650)(-800 1700);
WIRE 17 -1 (-800 1600)(-800 1650);
WIRE 17 -1 (-800 1550)(-800 1600);
WIRE 17 -1 (-800 1500)(-800 1550);
WIRE 17 -1 (-800 1450)(-800 1500);
WIRE 17 -1 (-800 1400)(-800 1450);
WIRE 17 -1 (-800 1350)(-800 1400);
WIRE 17 -1 (-800 1300)(-800 1350);
WIRE 17 -1 (-800 1250)(-800 1300);
WIRE 17 -1 (-800 1200)(-800 1250);
WIRE 17 -1 (1950 2450)(1950 2550);
WIRE 17 -1 (1950 2550)(1950 2650);
WIRE 17 -1 (1950 2650)(1950 2750);
WIRE 17 -1 (1950 2850)(1950 2750);
WIRE 17 -1 (1950 2850)(1950 2950);
WIRE 17 -1 (1950 2950)(1950 3050);
WIRE 17 -1 (1950 3050)(1950 3150);
WIRE 17 -1 (1950 3150)(1950 3250);
WIRE 17 -1 (1950 3250)(1950 3350);
WIRE 17 -1 (1950 3350)(2975 3350);
FORCEPROP 2 LAST SIG_NAME M_E_CPU1_SB_DQS_DP<9:0>
J 0
(2190 3360);
DISPLAY 0.680851 (2190 3360);
PAINT WHITE (2190 3360);
WIRE 17 -1 (1950 3500)(1950 3600);
WIRE 17 -1 (1950 3600)(1950 3700);
WIRE 17 -1 (1950 3700)(1950 3800);
WIRE 17 -1 (1950 3900)(1950 3800);
WIRE 17 -1 (1950 3900)(1950 4000);
WIRE 17 -1 (1950 4000)(1950 4100);
WIRE 17 -1 (1950 4100)(1950 4200);
WIRE 17 -1 (1950 4200)(1950 4300);
WIRE 17 -1 (1950 4300)(1950 4400);
WIRE 17 -1 (1950 4400)(2975 4400);
FORCEPROP 2 LAST SIG_NAME M_E_CPU1_SA_DQS_DP<9:0>
J 0
(2190 4410);
DISPLAY 0.680851 (2190 4410);
PAINT WHITE (2190 4410);
WIRE 17 -1 (2125 2400)(2125 2500);
WIRE 17 -1 (2125 2500)(2125 2600);
WIRE 17 -1 (2125 2600)(2125 2700);
WIRE 17 -1 (2125 2800)(2125 2700);
WIRE 17 -1 (2125 2800)(2125 2900);
WIRE 17 -1 (2125 2900)(2125 3000);
WIRE 17 -1 (2125 3000)(2125 3100);
WIRE 17 -1 (2125 3100)(2125 3200);
WIRE 17 -1 (2125 3200)(2125 3300);
WIRE 17 -1 (2125 3300)(2975 3300);
FORCEPROP 2 LAST SIG_NAME M_E_CPU1_SB_DQS_DN<9:0>
J 0
(2190 3310);
DISPLAY 0.680851 (2190 3310);
PAINT WHITE (2190 3310);
WIRE 17 -1 (2125 3450)(2125 3550);
WIRE 17 -1 (2125 3550)(2125 3650);
WIRE 17 -1 (2125 3650)(2125 3750);
WIRE 17 -1 (2125 3850)(2125 3750);
WIRE 17 -1 (2125 3850)(2125 3950);
WIRE 17 -1 (2125 3950)(2125 4050);
WIRE 17 -1 (2125 4050)(2125 4150);
WIRE 17 -1 (2125 4150)(2125 4250);
WIRE 17 -1 (2125 4250)(2125 4350);
WIRE 17 -1 (2125 4350)(2975 4350);
FORCEPROP 2 LAST SIG_NAME M_E_CPU1_SA_DQS_DN<9:0>
J 0
(2190 4360);
DISPLAY 0.680851 (2190 4360);
PAINT WHITE (2190 4360);
WIRE 16 -1 (-3325 2200)(-3325 1925);
WIRE 16 -1 (875 600)(875 775);
WIRE 16 -1 (3575 4875)(3575 4375);
WIRE 16 -1 (1875 775)(1875 725);
WIRE 16 -1 (-2275 50)(-2275 125);
WIRE 16 -1 (875 400)(875 175);
WIRE 16 -1 (2500 175)(2500 250);
WIRE 16 -1 (3575 725)(3575 1125);
WIRE 16 -1 (5275 1025)(5275 725);
WIRE 16 -1 (5275 1075)(5275 1025);
WIRE 16 -1 (5025 1025)(5275 1025);
WIRE 16 -1 (1875 725)(1875 600);
WIRE 16 -1 (2500 725)(1875 725);
WIRE 16 -1 (2500 600)(2500 725);
WIRE 16 -1 (-2275 2025)(-3400 2025);
FORCEPROP 2 LAST SIG_NAME M_E_CPU1_ALERT_N
J 0
(-3312 2034);
DISPLAY 0.680851 (-3312 2034);
PAINT WHITE (-3312 2034);
WIRE 16 -1 (-3800 1675)(-3600 1675);
WIRE 16 -1 (-3800 1675)(-3800 1775);
WIRE 16 -1 (-2275 1775)(-3800 1775);
FORCEPROP 2 LAST SIG_NAME I3C_SPD_DDREFGH_CPU1_LVC1_SCL_R2
J 0
(-3335 1785);
DISPLAY 0.680851 (-3335 1785);
PAINT WHITE (-3335 1785);
WIRE 16 -1 (-2275 1825)(-3275 1825);
FORCEPROP 2 LAST SIG_NAME I3C_SPD_DDREFGH_CPU1_LVC1_SDA
J 0
(-3285 1835);
DISPLAY 0.680851 (-3285 1835);
PAINT WHITE (-3285 1835);
WIRE 16 -1 (-2275 1875)(-3275 1875);
FORCEPROP 2 LAST SIG_NAME PD_CHE_CPU1_DIMM2_SAA
J 0
(-3285 1885);
DISPLAY 0.680851 (-3285 1885);
PAINT WHITE (-3285 1885);
WIRE 16 -1 (-3325 1925)(-2275 1925);
WIRE 16 -1 (-2650 2075)(-2275 2075);
WIRE 16 -1 (-2650 2125)(-3400 2125);
FORCEPROP 2 LAST SIG_NAME RST_M_EF_CPU1_FPGA_N
J 0
(-3312 2134);
DISPLAY 0.680851 (-3312 2134);
PAINT WHITE (-3312 2134);
WIRE 16 -1 (-2650 2125)(-2650 2075);
WIRE 16 -1 (-2450 2175)(-2275 2175);
WIRE 16 -1 (-2450 2225)(-2275 2225);
WIRE 16 -1 (-2175 1625)(-2225 1625);
WIRE 16 -1 (-3400 1675)(-2175 1675);
FORCEPROP 2 LAST SIG_NAME I3C_SPD_DDREFGH_CPU1_LVC1_SCL
J 0
(-3235 1685);
DISPLAY 0.680851 (-3235 1685);
PAINT WHITE (-3235 1685);
WIRE 16 -1 (-2175 1675)(-2175 1625);
WIRE 16 -1 (-2275 1525)(-3375 1525);
FORCEPROP 2 LAST SIG_NAME PWRGD_CHE_CPU1_DIMM2
J 0
(-3287 1534);
DISPLAY 0.680851 (-3287 1534);
PAINT WHITE (-3287 1534);
WIRE 16 -1 (1750 4325)(2025 4325);
WIRE 16 -1 (1750 4225)(2025 4225);
WIRE 16 -1 (1750 4125)(2025 4125);
WIRE 16 -1 (1750 4025)(2025 4025);
WIRE 16 -1 (1750 3925)(2025 3925);
WIRE 16 -1 (1750 3725)(2025 3725);
WIRE 16 -1 (1750 3825)(2025 3825);
WIRE 16 -1 (1750 3625)(2025 3625);
WIRE 16 -1 (1750 3525)(2025 3525);
WIRE 16 -1 (1750 3425)(2025 3425);
WIRE 16 -1 (1750 3275)(2025 3275);
WIRE 16 -1 (1750 3175)(2025 3175);
WIRE 16 -1 (1750 3075)(2025 3075);
WIRE 16 -1 (1750 2975)(2025 2975);
WIRE 16 -1 (1750 2875)(2025 2875);
WIRE 16 -1 (1750 2775)(2025 2775);
WIRE 16 -1 (1750 2575)(2025 2575);
WIRE 16 -1 (1750 2675)(2025 2675);
WIRE 16 -1 (1750 2475)(2025 2475);
WIRE 16 -1 (1750 2375)(2025 2375);
WIRE 16 -1 (1750 4375)(1850 4375);
WIRE 16 -1 (1750 4275)(1850 4275);
WIRE 16 -1 (1750 4175)(1850 4175);
WIRE 16 -1 (1750 4075)(1850 4075);
WIRE 16 -1 (1750 3975)(1850 3975);
WIRE 16 -1 (1750 3875)(1850 3875);
WIRE 16 -1 (1750 3775)(1850 3775);
WIRE 16 -1 (1750 3675)(1850 3675);
WIRE 16 -1 (1750 3575)(1850 3575);
WIRE 16 -1 (1750 3475)(1850 3475);
WIRE 16 -1 (1750 3325)(1850 3325);
WIRE 16 -1 (1750 3225)(1850 3225);
WIRE 16 -1 (1750 3125)(1850 3125);
WIRE 16 -1 (1750 3025)(1850 3025);
WIRE 16 -1 (1750 2925)(1850 2925);
WIRE 16 -1 (1750 2825)(1850 2825);
WIRE 16 -1 (1750 2725)(1850 2725);
WIRE 16 -1 (1750 2625)(1850 2625);
WIRE 16 -1 (1750 2525)(1850 2525);
WIRE 16 -1 (1750 2425)(1850 2425);
WIRE 16 -1 (-2450 2725)(-2275 2725);
WIRE 16 -1 (-2275 1175)(-3375 1175);
FORCEPROP 2 LAST SIG_NAME TP_CHE_CPU1_DIMM2_FRU_1
J 0
(-3287 1184);
DISPLAY 0.680851 (-3287 1184);
PAINT WHITE (-3287 1184);
WIRE 16 -1 (-2275 1125)(-3375 1125);
FORCEPROP 2 LAST SIG_NAME TP_CHE_CPU1_DIMM2_FRU_0
J 0
(-3287 1134);
DISPLAY 0.680851 (-3287 1134);
PAINT WHITE (-3287 1134);
WIRE 16 -1 (3825 4275)(3575 4275);
WIRE 16 -1 (3575 4325)(3575 4275);
WIRE 16 -1 (3575 4325)(3825 4325);
WIRE 16 -1 (3575 4375)(3575 4325);
WIRE 16 -1 (3825 4375)(3575 4375);
WIRE 16 -1 (-1075 3325)(-900 3325);
WIRE 16 -1 (3825 4225)(3575 4225);
WIRE 16 -1 (3575 4175)(3575 4225);
WIRE 16 -1 (3575 4175)(3825 4175);
WIRE 16 -1 (3575 4125)(3575 4175);
WIRE 16 -1 (3825 4125)(3575 4125);
WIRE 16 -1 (3575 4075)(3825 4075);
WIRE 16 -1 (3575 4075)(3575 4125);
WIRE 16 -1 (3575 4025)(3575 4075);
WIRE 16 -1 (3575 4025)(3825 4025);
WIRE 16 -1 (3575 3975)(3575 4025);
WIRE 16 -1 (3575 3975)(3825 3975);
WIRE 16 -1 (3575 3925)(3575 3975);
WIRE 16 -1 (3575 3925)(3825 3925);
WIRE 16 -1 (3575 3875)(3575 3925);
WIRE 16 -1 (3575 3875)(3825 3875);
WIRE 16 -1 (3575 3825)(3575 3875);
WIRE 16 -1 (3575 3825)(3825 3825);
WIRE 16 -1 (3575 3775)(3575 3825);
WIRE 16 -1 (3575 3775)(3825 3775);
WIRE 16 -1 (3575 3725)(3575 3775);
WIRE 16 -1 (3575 3725)(3825 3725);
WIRE 16 -1 (3575 3675)(3575 3725);
WIRE 16 -1 (3575 3675)(3825 3675);
WIRE 16 -1 (3575 3625)(3575 3675);
WIRE 16 -1 (3825 3625)(3575 3625);
WIRE 16 -1 (3575 3575)(3575 3625);
WIRE 16 -1 (3575 3575)(3825 3575);
WIRE 16 -1 (3575 3525)(3575 3575);
WIRE 16 -1 (3575 3525)(3825 3525);
WIRE 16 -1 (3575 3475)(3575 3525);
WIRE 16 -1 (3575 3475)(3825 3475);
WIRE 16 -1 (3575 3425)(3575 3475);
WIRE 16 -1 (3575 3425)(3825 3425);
WIRE 16 -1 (3575 3375)(3575 3425);
WIRE 16 -1 (3575 3375)(3825 3375);
WIRE 16 -1 (3575 3325)(3575 3375);
WIRE 16 -1 (3575 3325)(3825 3325);
WIRE 16 -1 (3575 3275)(3575 3325);
WIRE 16 -1 (3575 3275)(3825 3275);
WIRE 16 -1 (3575 3225)(3575 3275);
WIRE 16 -1 (3575 3225)(3825 3225);
WIRE 16 -1 (3575 3175)(3575 3225);
WIRE 16 -1 (3575 3175)(3825 3175);
WIRE 16 -1 (3575 3125)(3575 3175);
WIRE 16 -1 (3825 3125)(3575 3125);
WIRE 16 -1 (3575 3075)(3575 3125);
WIRE 16 -1 (3575 3075)(3825 3075);
WIRE 16 -1 (3575 3025)(3825 3025);
WIRE 16 -1 (3575 3025)(3575 3075);
WIRE 16 -1 (3575 2975)(3575 3025);
WIRE 16 -1 (3575 2975)(3825 2975);
WIRE 16 -1 (3575 2925)(3575 2975);
WIRE 16 -1 (3575 2925)(3825 2925);
WIRE 16 -1 (3575 2875)(3575 2925);
WIRE 16 -1 (3575 2875)(3825 2875);
WIRE 16 -1 (3575 2825)(3575 2875);
WIRE 16 -1 (3575 2825)(3825 2825);
WIRE 16 -1 (3575 2775)(3575 2825);
WIRE 16 -1 (3575 2775)(3825 2775);
WIRE 16 -1 (3575 2725)(3575 2775);
WIRE 16 -1 (3575 2725)(3825 2725);
WIRE 16 -1 (3575 2675)(3575 2725);
WIRE 16 -1 (3575 2675)(3825 2675);
WIRE 16 -1 (3575 2625)(3575 2675);
WIRE 16 -1 (3825 2625)(3575 2625);
WIRE 16 -1 (3575 2575)(3575 2625);
WIRE 16 -1 (3575 2575)(3825 2575);
WIRE 16 -1 (3575 2525)(3575 2575);
WIRE 16 -1 (3575 2525)(3825 2525);
WIRE 16 -1 (3575 2475)(3575 2525);
WIRE 16 -1 (3575 2475)(3825 2475);
WIRE 16 -1 (3575 2425)(3575 2475);
WIRE 16 -1 (3575 2425)(3825 2425);
WIRE 16 -1 (3575 2375)(3575 2425);
WIRE 16 -1 (3575 2375)(3825 2375);
WIRE 16 -1 (3575 2325)(3575 2375);
WIRE 16 -1 (3575 2325)(3825 2325);
WIRE 16 -1 (3575 2275)(3575 2325);
WIRE 16 -1 (3575 2275)(3825 2275);
WIRE 16 -1 (3575 2225)(3575 2275);
WIRE 16 -1 (3575 2225)(3825 2225);
WIRE 16 -1 (3575 2175)(3575 2225);
WIRE 16 -1 (3575 2175)(3825 2175);
WIRE 16 -1 (3575 2125)(3575 2175);
WIRE 16 -1 (3825 2125)(3575 2125);
WIRE 16 -1 (3575 2075)(3575 2125);
WIRE 16 -1 (3575 2075)(3825 2075);
WIRE 16 -1 (3575 2025)(3825 2025);
WIRE 16 -1 (3575 2025)(3575 2075);
WIRE 16 -1 (3575 1975)(3575 2025);
WIRE 16 -1 (3575 1975)(3825 1975);
WIRE 16 -1 (3575 1925)(3575 1975);
WIRE 16 -1 (3575 1925)(3825 1925);
WIRE 16 -1 (3575 1875)(3575 1925);
WIRE 16 -1 (3575 1875)(3825 1875);
WIRE 16 -1 (3575 1825)(3575 1875);
WIRE 16 -1 (3575 1825)(3825 1825);
WIRE 16 -1 (3575 1775)(3575 1825);
WIRE 16 -1 (3575 1775)(3825 1775);
WIRE 16 -1 (3575 1725)(3575 1775);
WIRE 16 -1 (3575 1725)(3825 1725);
WIRE 16 -1 (3575 1675)(3575 1725);
WIRE 16 -1 (3575 1675)(3825 1675);
WIRE 16 -1 (3575 1625)(3575 1675);
WIRE 16 -1 (3825 1625)(3575 1625);
WIRE 16 -1 (3575 1575)(3575 1625);
WIRE 16 -1 (3575 1575)(3825 1575);
WIRE 16 -1 (3575 1525)(3575 1575);
WIRE 16 -1 (3575 1525)(3825 1525);
WIRE 16 -1 (3575 1475)(3575 1525);
WIRE 16 -1 (3575 1475)(3825 1475);
WIRE 16 -1 (3575 1425)(3575 1475);
WIRE 16 -1 (3575 1425)(3825 1425);
WIRE 16 -1 (3575 1375)(3575 1425);
WIRE 16 -1 (3575 1375)(3825 1375);
WIRE 16 -1 (3575 1325)(3575 1375);
WIRE 16 -1 (3575 1325)(3825 1325);
WIRE 16 -1 (3575 1275)(3575 1325);
WIRE 16 -1 (3575 1275)(3825 1275);
WIRE 16 -1 (3575 1225)(3575 1275);
WIRE 16 -1 (3575 1225)(3825 1225);
WIRE 16 -1 (3575 1175)(3575 1225);
WIRE 16 -1 (3575 1175)(3825 1175);
WIRE 16 -1 (3575 1125)(3575 1175);
WIRE 16 -1 (3575 1125)(3825 1125);
WIRE 16 -1 (5025 1075)(5275 1075);
WIRE 16 -1 (5025 1125)(5275 1125);
WIRE 16 -1 (5275 1125)(5275 1075);
WIRE 16 -1 (5025 1225)(5275 1225);
WIRE 16 -1 (5275 1225)(5275 1125);
WIRE 16 -1 (5025 1275)(5275 1275);
WIRE 16 -1 (5275 1275)(5275 1225);
WIRE 16 -1 (5025 1325)(5275 1325);
WIRE 16 -1 (5275 1275)(5275 1325);
WIRE 16 -1 (5025 1375)(5275 1375);
WIRE 16 -1 (5275 1375)(5275 1325);
WIRE 16 -1 (5025 1425)(5275 1425);
WIRE 16 -1 (5275 1425)(5275 1375);
WIRE 16 -1 (5025 1475)(5275 1475);
WIRE 16 -1 (5275 1475)(5275 1425);
WIRE 16 -1 (5025 1525)(5275 1525);
WIRE 16 -1 (5275 1525)(5275 1475);
WIRE 16 -1 (5025 1575)(5275 1575);
WIRE 16 -1 (5275 1575)(5275 1525);
WIRE 16 -1 (5025 1625)(5275 1625);
WIRE 16 -1 (5275 1625)(5275 1575);
WIRE 16 -1 (5275 1675)(5025 1675);
WIRE 16 -1 (5275 1675)(5275 1625);
WIRE 16 -1 (5275 1725)(5025 1725);
WIRE 16 -1 (5275 1725)(5275 1675);
WIRE 16 -1 (5275 1775)(5025 1775);
WIRE 16 -1 (5275 1775)(5275 1725);
WIRE 16 -1 (5025 1825)(5275 1825);
WIRE 16 -1 (5275 1775)(5275 1825);
WIRE 16 -1 (5275 1875)(5025 1875);
WIRE 16 -1 (5275 1825)(5275 1875);
WIRE 16 -1 (5275 1925)(5025 1925);
WIRE 16 -1 (5275 1925)(5275 1875);
WIRE 16 -1 (5275 1975)(5025 1975);
WIRE 16 -1 (5275 1975)(5275 1925);
WIRE 16 -1 (5275 2025)(5025 2025);
WIRE 16 -1 (5275 2025)(5275 1975);
WIRE 16 -1 (5275 2075)(5275 2025);
WIRE 16 -1 (5025 2075)(5275 2075);
WIRE 16 -1 (5025 2125)(5275 2125);
WIRE 16 -1 (5275 2125)(5275 2075);
WIRE 16 -1 (5025 2175)(5275 2175);
WIRE 16 -1 (5275 2125)(5275 2175);
WIRE 16 -1 (5025 2225)(5275 2225);
WIRE 16 -1 (5275 2225)(5275 2175);
WIRE 16 -1 (5025 2275)(5275 2275);
WIRE 16 -1 (5275 2275)(5275 2225);
WIRE 16 -1 (5025 2325)(5275 2325);
WIRE 16 -1 (5275 2325)(5275 2275);
WIRE 16 -1 (5025 2375)(5275 2375);
WIRE 16 -1 (5275 2375)(5275 2325);
WIRE 16 -1 (5025 2425)(5275 2425);
WIRE 16 -1 (5275 2425)(5275 2375);
WIRE 16 -1 (5275 2475)(5025 2475);
WIRE 16 -1 (5275 2475)(5275 2425);
WIRE 16 -1 (5275 2525)(5025 2525);
WIRE 16 -1 (5275 2525)(5275 2475);
WIRE 16 -1 (5025 2575)(5275 2575);
WIRE 16 -1 (5275 2575)(5275 2525);
WIRE 16 -1 (5025 2625)(5275 2625);
WIRE 16 -1 (5275 2625)(5275 2575);
WIRE 16 -1 (5025 2675)(5275 2675);
WIRE 16 -1 (5275 2625)(5275 2675);
WIRE 16 -1 (5025 2725)(5275 2725);
WIRE 16 -1 (5275 2725)(5275 2675);
WIRE 16 -1 (5025 2775)(5275 2775);
WIRE 16 -1 (5275 2775)(5275 2725);
WIRE 16 -1 (5025 2825)(5275 2825);
WIRE 16 -1 (5275 2825)(5275 2775);
WIRE 16 -1 (5025 2875)(5275 2875);
WIRE 16 -1 (5275 2875)(5275 2825);
WIRE 16 -1 (5025 2925)(5275 2925);
WIRE 16 -1 (5275 2925)(5275 2875);
WIRE 16 -1 (5275 2975)(5025 2975);
WIRE 16 -1 (5275 2975)(5275 2925);
WIRE 16 -1 (5275 3025)(5025 3025);
WIRE 16 -1 (5275 3025)(5275 2975);
WIRE 16 -1 (5025 3075)(5275 3075);
WIRE 16 -1 (5275 3075)(5275 3025);
WIRE 16 -1 (5025 3125)(5275 3125);
WIRE 16 -1 (5275 3125)(5275 3075);
WIRE 16 -1 (5025 3175)(5275 3175);
WIRE 16 -1 (5275 3125)(5275 3175);
WIRE 16 -1 (5025 3225)(5275 3225);
WIRE 16 -1 (5275 3225)(5275 3175);
WIRE 16 -1 (5025 3275)(5275 3275);
WIRE 16 -1 (5275 3275)(5275 3225);
WIRE 16 -1 (5025 3325)(5275 3325);
WIRE 16 -1 (5275 3325)(5275 3275);
WIRE 16 -1 (5025 3375)(5275 3375);
WIRE 16 -1 (5275 3375)(5275 3325);
WIRE 16 -1 (5025 3425)(5275 3425);
WIRE 16 -1 (5275 3425)(5275 3375);
WIRE 16 -1 (5275 3475)(5025 3475);
WIRE 16 -1 (5275 3475)(5275 3425);
WIRE 16 -1 (5275 3525)(5025 3525);
WIRE 16 -1 (5275 3525)(5275 3475);
WIRE 16 -1 (5025 3575)(5275 3575);
WIRE 16 -1 (5275 3575)(5275 3525);
WIRE 16 -1 (5025 3625)(5275 3625);
WIRE 16 -1 (5275 3625)(5275 3575);
WIRE 16 -1 (5025 3675)(5275 3675);
WIRE 16 -1 (5275 3625)(5275 3675);
WIRE 16 -1 (5025 3725)(5275 3725);
WIRE 16 -1 (5275 3725)(5275 3675);
WIRE 16 -1 (5025 3775)(5275 3775);
WIRE 16 -1 (5275 3775)(5275 3725);
WIRE 16 -1 (5025 3825)(5275 3825);
WIRE 16 -1 (5275 3825)(5275 3775);
WIRE 16 -1 (5025 3875)(5275 3875);
WIRE 16 -1 (5275 3875)(5275 3825);
WIRE 16 -1 (5025 3925)(5275 3925);
WIRE 16 -1 (5275 3925)(5275 3875);
WIRE 16 -1 (5025 3975)(5275 3975);
WIRE 16 -1 (5275 3975)(5275 3925);
WIRE 16 -1 (5025 4025)(5275 4025);
WIRE 16 -1 (5275 4025)(5275 3975);
WIRE 16 -1 (5025 4075)(5275 4075);
WIRE 16 -1 (5275 4075)(5275 4025);
WIRE 16 -1 (5275 4125)(5275 4075);
WIRE 16 -1 (5025 4125)(5275 4125);
WIRE 16 -1 (5025 4175)(5275 4175);
WIRE 16 -1 (5275 4175)(5275 4125);
WIRE 16 -1 (5025 4225)(5275 4225);
WIRE 16 -1 (5275 4225)(5275 4175);
WIRE 16 -1 (5025 4275)(5275 4275);
WIRE 16 -1 (5275 4275)(5275 4225);
WIRE 16 -1 (5025 4325)(5275 4325);
WIRE 16 -1 (5275 4325)(5275 4275);
WIRE 16 -1 (5275 4375)(5275 4325);
WIRE 16 -1 (5025 4375)(5275 4375);
WIRE 16 -1 (-1075 2725)(-900 2725);
WIRE 16 -1 (-1075 3175)(-900 3175);
WIRE 16 -1 (-2275 1225)(-3375 1225);
FORCEPROP 2 LAST SIG_NAME TP_CHE_CPU1_DIMM2_FRU_2
J 0
(-3287 1234);
DISPLAY 0.680851 (-3287 1234);
PAINT WHITE (-3287 1234);
WIRE 16 -1 (-2275 1275)(-3375 1275);
FORCEPROP 2 LAST SIG_NAME TP_CHE_CPU1_DIMM2_FRU_3
J 0
(-3287 1284);
DISPLAY 0.680851 (-3287 1284);
PAINT WHITE (-3287 1284);
WIRE 16 -1 (-2275 1325)(-3375 1325);
FORCEPROP 2 LAST SIG_NAME TP_CHE_CPU1_DIMM2_FRU_4
J 0
(-3287 1334);
DISPLAY 0.680851 (-3287 1334);
PAINT WHITE (-3287 1334);
WIRE 16 -1 (-2275 1375)(-3375 1375);
FORCEPROP 2 LAST SIG_NAME TP_CHE_CPU1_DIMM2_FRU_5
J 0
(-3287 1384);
DISPLAY 0.680851 (-3287 1384);
PAINT WHITE (-3287 1384);
WIRE 16 -1 (-2275 1425)(-3375 1425);
FORCEPROP 2 LAST SIG_NAME TP_CHE_CPU1_DIMM2_FRU_6
J 0
(-3287 1434);
DISPLAY 0.680851 (-3287 1434);
PAINT WHITE (-3287 1434);
WIRE 16 -1 (-2275 3525)(-3375 3525);
FORCEPROP 2 LAST SIG_NAME M_E_CPU1_SB_PAR
J 0
(-3287 3534);
DISPLAY 0.680851 (-3287 3534);
PAINT WHITE (-3287 3534);
WIRE 16 -1 (-2275 3575)(-3375 3575);
FORCEPROP 2 LAST SIG_NAME M_E_CPU1_SA_PAR
J 0
(-3287 3584);
DISPLAY 0.680851 (-3287 3584);
PAINT WHITE (-3287 3584);
WIRE 16 -1 (-2275 925)(-3375 925);
FORCEPROP 2 LAST SIG_NAME M_E_CPU1_SB_RSP<1>
J 0
(-3287 934);
DISPLAY 0.680851 (-3287 934);
PAINT WHITE (-3287 934);
WIRE 16 -1 (-2275 975)(-3375 975);
FORCEPROP 2 LAST SIG_NAME M_E_CPU1_SA_RSP<1>
J 0
(-3287 984);
DISPLAY 0.680851 (-3287 984);
PAINT WHITE (-3287 984);
WIRE 16 -1 (-1075 1175)(-900 1175);
WIRE 16 -1 (-1075 1225)(-900 1225);
WIRE 16 -1 (-1075 1275)(-900 1275);
WIRE 16 -1 (-1075 1325)(-900 1325);
WIRE 16 -1 (-1075 1375)(-900 1375);
WIRE 16 -1 (-1075 1425)(-900 1425);
WIRE 16 -1 (-1075 1475)(-900 1475);
WIRE 16 -1 (-1075 1525)(-900 1525);
WIRE 16 -1 (-1075 1575)(-900 1575);
WIRE 16 -1 (-1075 1625)(-900 1625);
WIRE 16 -1 (-1075 1675)(-900 1675);
WIRE 16 -1 (-1075 1725)(-900 1725);
WIRE 16 -1 (-1075 1775)(-900 1775);
WIRE 16 -1 (-1075 1825)(-900 1825);
WIRE 16 -1 (-1075 1875)(-900 1875);
WIRE 16 -1 (-1075 1925)(-900 1925);
WIRE 16 -1 (-1075 1975)(-900 1975);
WIRE 16 -1 (-1075 2025)(-900 2025);
WIRE 16 -1 (-1075 2075)(-900 2075);
WIRE 16 -1 (-1075 2125)(-900 2125);
WIRE 16 -1 (-1075 2175)(-900 2175);
WIRE 16 -1 (-1075 2225)(-900 2225);
WIRE 16 -1 (-1075 2275)(-900 2275);
WIRE 16 -1 (-1075 2325)(-900 2325);
WIRE 16 -1 (-1075 2375)(-900 2375);
WIRE 16 -1 (-1075 2425)(-900 2425);
WIRE 16 -1 (-1075 2475)(-900 2475);
WIRE 16 -1 (-1075 2525)(-900 2525);
WIRE 16 -1 (-1075 2575)(-900 2575);
WIRE 16 -1 (-1075 2625)(-900 2625);
WIRE 16 -1 (-1075 2675)(-900 2675);
WIRE 16 -1 (-1075 2825)(-900 2825);
WIRE 16 -1 (-1075 2875)(-900 2875);
WIRE 16 -1 (-1075 2925)(-900 2925);
WIRE 16 -1 (-1075 2975)(-900 2975);
WIRE 16 -1 (-1075 3025)(-900 3025);
WIRE 16 -1 (-1075 3075)(-900 3075);
WIRE 16 -1 (-1075 3125)(-900 3125);
WIRE 16 -1 (-1075 3225)(-900 3225);
WIRE 16 -1 (-1075 3275)(-900 3275);
WIRE 16 -1 (-1075 3375)(-900 3375);
WIRE 16 -1 (-1075 3425)(-900 3425);
WIRE 16 -1 (-1075 3475)(-900 3475);
WIRE 16 -1 (-1075 3525)(-900 3525);
WIRE 16 -1 (-1075 3575)(-900 3575);
WIRE 16 -1 (-1075 3625)(-900 3625);
WIRE 16 -1 (-1075 3675)(-900 3675);
WIRE 16 -1 (-1075 3725)(-900 3725);
WIRE 16 -1 (-1075 3775)(-900 3775);
WIRE 16 -1 (-1075 3825)(-900 3825);
WIRE 16 -1 (-1075 3875)(-900 3875);
WIRE 16 -1 (-1075 3925)(-900 3925);
WIRE 16 -1 (-1075 3975)(-900 3975);
WIRE 16 -1 (-1075 4025)(-900 4025);
WIRE 16 -1 (-1075 4075)(-900 4075);
WIRE 16 -1 (-1075 4125)(-900 4125);
WIRE 16 -1 (-1075 4175)(-900 4175);
WIRE 16 -1 (-1075 4225)(-900 4225);
WIRE 16 -1 (-1075 4275)(-900 4275);
WIRE 16 -1 (-1075 4325)(-900 4325);
WIRE 16 -1 (-2275 3275)(-3375 3275);
FORCEPROP 2 LAST SIG_NAME M_E_CPU1_SB_CS_N<3>
J 0
(-3287 3284);
DISPLAY 0.680851 (-3287 3284);
PAINT WHITE (-3287 3284);
WIRE 16 -1 (-2275 3425)(-3375 3425);
FORCEPROP 2 LAST SIG_NAME M_E_CPU1_SA_CS_N<3>
J 0
(-3287 3434);
DISPLAY 0.680851 (-3287 3434);
PAINT WHITE (-3287 3434);
WIRE 16 -1 (-2275 3225)(-3375 3225);
FORCEPROP 2 LAST SIG_NAME M_E_CPU1_SB_CS_N<2>
J 0
(-3287 3234);
DISPLAY 0.680851 (-3287 3234);
PAINT WHITE (-3287 3234);
WIRE 16 -1 (-2275 3375)(-3375 3375);
FORCEPROP 2 LAST SIG_NAME M_E_CPU1_SA_CS_N<2>
J 0
(-3287 3384);
DISPLAY 0.680851 (-3287 3384);
PAINT WHITE (-3287 3384);
WIRE 16 -1 (-2275 3125)(-3375 3125);
FORCEPROP 2 LAST SIG_NAME M_E_CPU1_CLK_DP<1>
J 0
(-3287 3134);
DISPLAY 0.680851 (-3287 3134);
PAINT WHITE (-3287 3134);
WIRE 16 -1 (-2275 3075)(-3375 3075);
FORCEPROP 2 LAST SIG_NAME M_E_CPU1_CLK_DN<1>
J 0
(-3287 3084);
DISPLAY 0.680851 (-3287 3084);
PAINT WHITE (-3287 3084);
WIRE 16 -1 (-2450 2275)(-2275 2275);
WIRE 16 -1 (-2450 2325)(-2275 2325);
WIRE 16 -1 (-2450 2375)(-2275 2375);
WIRE 16 -1 (-2450 2425)(-2275 2425);
WIRE 16 -1 (-2450 2475)(-2275 2475);
WIRE 16 -1 (-2450 2625)(-2275 2625);
WIRE 16 -1 (-2450 2775)(-2275 2775);
WIRE 16 -1 (-2450 2875)(-2275 2875);
WIRE 16 -1 (-2450 2925)(-2275 2925);
WIRE 16 -1 (-2450 3975)(-2275 3975);
WIRE 16 -1 (-2450 4375)(-2275 4375);
WIRE 16 -1 (-2450 3925)(-2275 3925);
WIRE 16 -1 (-2450 4325)(-2275 4325);
WIRE 16 -1 (-2450 3875)(-2275 3875);
WIRE 16 -1 (-2450 4275)(-2275 4275);
WIRE 16 -1 (-2450 3825)(-2275 3825);
WIRE 16 -1 (-2450 4225)(-2275 4225);
WIRE 16 -1 (-2450 3775)(-2275 3775);
WIRE 16 -1 (-2450 4175)(-2275 4175);
WIRE 16 -1 (-2450 3725)(-2275 3725);
WIRE 16 -1 (-2450 4125)(-2275 4125);
WIRE 16 -1 (-2450 3675)(-2275 3675);
WIRE 16 -1 (-2450 4075)(-2275 4075);
WIRE 16 -1 (-2450 2525)(-2275 2525);
WIRE 16 -1 (-2450 2675)(-2275 2675);
WIRE 16 -1 (-2450 2825)(-2275 2825);
WIRE 16 -1 (-2450 2975)(-2275 2975);
WIRE 16 -1 (-1075 4375)(-900 4375);
WIRE 16 -1 (-2275 425)(-3375 425);
FORCEPROP 2 LAST SIG_NAME PD_CHE_CPU1_DIMM2_SAA
J 0
(-3287 434);
DISPLAY 0.680851 (-3287 434);
PAINT WHITE (-3287 434);
WIRE 16 -1 (-2275 325)(-2275 425);
WIRE 16 -1 (1875 250)(1875 400);
WIRE 16 -1 (2500 250)(1875 250);
WIRE 16 -1 (2500 250)(2500 400);
WIRE 16 3135 (525 1000)(525 -300);
WIRE 16 3135 (3125 1000)(525 1000);
WIRE 16 3135 (525 -300)(3125 -300);
WIRE 16 3135 (3125 -300)(3125 1000);
DOT 1 (3575 3025);
DOT 1 (3575 2975);
DOT 1 (3575 3225);
DOT 1 (3575 3525);
DOT 1 (3575 3325);
DOT 1 (5275 4325);
DOT 1 (5275 4275);
DOT 1 (5275 4225);
DOT 1 (5275 4125);
DOT 1 (5275 4175);
DOT 1 (5275 4075);
DOT 1 (5275 4025);
DOT 1 (5275 3975);
DOT 1 (5275 3925);
DOT 1 (5275 3875);
DOT 1 (5275 3825);
DOT 1 (5275 3775);
DOT 1 (5275 3725);
DOT 1 (5275 3675);
DOT 1 (5275 3625);
DOT 1 (5275 3575);
DOT 1 (5275 3525);
DOT 1 (5275 3475);
DOT 1 (5275 3425);
DOT 1 (5275 3375);
DOT 1 (5275 3325);
DOT 1 (5275 3275);
DOT 1 (5275 3225);
DOT 1 (5275 3175);
DOT 1 (5275 3125);
DOT 1 (5275 3075);
DOT 1 (5275 3025);
DOT 1 (5275 2975);
DOT 1 (5275 2925);
DOT 1 (5275 2875);
DOT 1 (5275 2825);
DOT 1 (5275 2775);
DOT 1 (5275 2725);
DOT 1 (5275 2675);
DOT 1 (5275 2625);
DOT 1 (5275 2575);
DOT 1 (5275 2525);
DOT 1 (5275 2475);
DOT 1 (5275 2425);
DOT 1 (5275 2375);
DOT 1 (5275 2325);
DOT 1 (5275 2275);
DOT 1 (5275 2225);
DOT 1 (5275 2175);
DOT 1 (5275 2125);
DOT 1 (5275 2075);
DOT 1 (5275 2025);
DOT 1 (5275 1975);
DOT 1 (5275 1925);
DOT 1 (5275 1875);
DOT 1 (5275 1825);
DOT 1 (5275 1775);
DOT 1 (5275 1725);
DOT 1 (5275 1675);
DOT 1 (5275 1575);
DOT 1 (5275 1625);
DOT 1 (5275 1525);
DOT 1 (5275 1475);
DOT 1 (5275 1425);
DOT 1 (5275 1375);
DOT 1 (5275 1325);
DOT 1 (5275 1275);
DOT 1 (5275 1225);
DOT 1 (3575 4375);
DOT 1 (3575 4325);
DOT 1 (3575 4125);
DOT 1 (3575 4175);
DOT 1 (3575 4075);
DOT 1 (3575 4025);
DOT 1 (3575 3975);
DOT 1 (3575 3875);
DOT 1 (3575 3925);
DOT 1 (3575 3825);
DOT 1 (3575 3775);
DOT 1 (3575 3725);
DOT 1 (3575 3625);
DOT 1 (3575 3675);
DOT 1 (3575 3575);
DOT 1 (3575 3475);
DOT 1 (3575 3425);
DOT 1 (3575 3375);
DOT 1 (3575 3275);
DOT 1 (3575 3125);
DOT 1 (3575 3175);
DOT 1 (3575 3075);
DOT 1 (3575 2925);
DOT 1 (3575 2875);
DOT 1 (3575 2825);
DOT 1 (3575 2775);
DOT 1 (3575 2725);
DOT 1 (3575 2675);
DOT 1 (3575 2625);
DOT 1 (3575 2575);
DOT 1 (3575 2525);
DOT 1 (3575 2475);
DOT 1 (3575 2425);
DOT 1 (3575 2375);
DOT 1 (3575 2325);
DOT 1 (3575 2275);
DOT 1 (3575 2225);
DOT 1 (3575 2175);
DOT 1 (3575 2125);
DOT 1 (3575 2075);
DOT 1 (3575 2025);
DOT 1 (3575 1975);
DOT 1 (3575 1925);
DOT 1 (3575 1875);
DOT 1 (3575 1825);
DOT 1 (3575 1775);
DOT 1 (3575 1725);
DOT 1 (3575 1675);
DOT 1 (3575 1625);
DOT 1 (3575 1575);
DOT 1 (3575 1525);
DOT 1 (3575 1475);
DOT 1 (3575 1425);
DOT 1 (3575 1375);
DOT 1 (3575 1325);
DOT 1 (3575 1275);
DOT 1 (3575 1225);
DOT 1 (3575 1175);
DOT 1 (3575 1125);
DOT 1 (2500 250);
DOT 1 (1875 725);
DOT 1 (5275 1125);
DOT 1 (5275 1075);
DOT 1 (5275 1025);
FORCENOTE
20210728 MODIFY FOR GT
(-3750 5075) 0;
DISPLAY LEFT (-3750 5075);
DISPLAY 2.510638 (-3750 5075);
PAINT PINK (-3750 5075);
QUIT
